G04 ================== begin FILE IDENTIFICATION RECORD ==================*
G04 Layout Name:  E:/<user>/9332_F0TG_MB_C/brd/0417/9332_F0TG_MB_C_V02_0417_0820.brd*
G04 Film Name:    pmb*
G04 File Format:  Gerber RS274X*
G04 File Origin:  Cadence Allegro 17.2-S081*
G04 Origin Date:  Wed Apr 19 14:49:58 2023*
G04 *
G04 Layer:  DRAWING FORMAT/TITLE_BLOCK_A*
G04 Layer:  VIA CLASS/PASTEMASK_BOTTOM*
G04 Layer:  PACKAGE GEOMETRY/PASTEMASK_BOTTOM*
G04 Layer:  DRAWING FORMAT/TITLE_BLOCK*
G04 Layer:  PIN/PASTEMASK_BOTTOM*
G04 Layer:  MANUFACTURING/PHOTOPLOT_OUTLINE*
G04 Layer:  DRAWING FORMAT/TITLE_DATA_PMB*
G04 *
G04 Offset:    (0.00 0.00)*
G04 Mirror:    No*
G04 Mode:      Positive*
G04 Rotation:  0*
G04 FullContactRelief:  No*
G04 UndefLineWidth:     6.00*
G04 ================== end FILE IDENTIFICATION RECORD ====================*
%FSLAX25Y25*MOIN*%
%IR0*IPPOS*OFA0.00000B0.00000*MIA0B0*SFA1.00000B1.00000*%
%AMMACRO91*
21,1,.016,.0041,0.0,0.0,30.*%
%ADD91MACRO91*%
%ADD29C,.02*%
%ADD96R,.0041X.016*%
%ADD89C,.03*%
%AMMACRO40*
21,1,.016,.0041,0.0,0.0,45.*%
%ADD40MACRO40*%
%ADD12R,.111X.095*%
%ADD81O,.137X.064*%
%ADD34R,.095X.111*%
%ADD25R,.007X.032*%
%ADD24R,.024X.007*%
%ADD41R,.026X.007*%
%ADD39C,.06*%
%ADD42R,.007X.026*%
%ADD28C,.061*%
%ADD30O,.137X.068*%
%ADD11C,.026*%
%ADD66C,.018*%
%ADD27C,.064*%
%ADD90C,.048*%
%ADD56C,.066*%
%ADD10C,.039*%
%ADD38R,.06X.06*%
%ADD31R,.061X.061*%
%ADD88R,.064X.064*%
%ADD92R,.048X.048*%
%ADD59R,.066X.066*%
%AMMACRO46*
4,1,28,-.00622,.00419,
-.00826,.00537,
-.00551,.01014,
-.005121,.010695,
-.004643,.011175,
-.004089,.011564,
-.003475,.011852,
-.002821,.012028,
-.002146,.012089,
-.001471,.012031,
-.000817,.011857,
-.000202,.011572,
-.00016,.01155,
.01008,.00564,
.010637,.005254,
.011122,.00478,
.011516,.00423,
.01181,.003619,
.011992,.002967,
.012059,.002293,
.012008,.001617,
.01184,.000961,
.01156,.000344,
.01154,.0003,
.00878,-.00447,
.00674,-.00329,
.00152,-.01232,
-.01143,-.00484,
-.00622,.00419,
0.0*
%
%ADD46MACRO46*%
%AMMACRO16*
4,1,28,-.00748,.00052,
-.00984,.00052,
-.00984,.00603,
-.009782,.006705,
-.009607,.007359,
-.009321,.007974,
-.008933,.008529,
-.008455,.009009,
-.0079,.009398,
-.007286,.009685,
-.006632,.009861,
-.005957,.00992,
-.00591,.00992,
.00591,.00992,
.006585,.009869,
.007242,.009701,
.007859,.009421,
.008418,.009039,
.008903,.008565,
.009297,.008015,
.009591,.007404,
.009773,.006751,
.00984,.006077,
.00984,.00603,
.00984,.00052,
.00748,.00052,
.00748,-.00991,
-.00748,-.00991,
-.00748,.00052,
0.0*
%
%ADD16MACRO16*%
%AMMACRO85*
4,1,44,.02953,.02165,
.029411,.023018,
.029056,.024344,
.028477,.025589,
.02769,.026714,
.026719,.027685,
.025595,.028473,
.024351,.029054,
.023025,.02941,
.021657,.02953,
.02165,.02953,
-.02161,.02953,
-.02173,.028155,
-.022087,.026822,
-.02267,.025571,
-.023461,.02444,
-.024436,.023464,
-.025567,.022672,
-.026817,.022088,
-.02815,.021731,
-.029525,.02161,
-.02953,.02161,
-.02953,-.02165,
-.029411,-.023018,
-.029056,-.024344,
-.028477,-.025589,
-.02769,-.026714,
-.026719,-.027685,
-.025595,-.028473,
-.024351,-.029054,
-.023025,-.02941,
-.021657,-.02953,
-.02165,-.02953,
.02165,-.02953,
.023018,-.029411,
.024344,-.029056,
.025589,-.028477,
.026714,-.02769,
.027685,-.026719,
.028473,-.025595,
.029054,-.024351,
.02941,-.023025,
.02953,-.021657,
.02953,-.02165,
.02953,.02165,
0.0*
%
%ADD85MACRO85*%
%AMMACRO18*
4,1,28,.00052,.00748,
.00052,.00984,
.00603,.00984,
.006705,.009782,
.007359,.009607,
.007974,.009321,
.008529,.008933,
.009009,.008455,
.009398,.0079,
.009685,.007286,
.009861,.006632,
.00992,.005957,
.00992,.00591,
.00992,-.00591,
.009869,-.006585,
.009701,-.007242,
.009421,-.007859,
.009039,-.008418,
.008565,-.008903,
.008015,-.009297,
.007404,-.009591,
.006751,-.009773,
.006077,-.00984,
.00603,-.00984,
.00052,-.00984,
.00052,-.00748,
-.00991,-.00748,
-.00991,.00748,
.00052,.00748,
0.0*
%
%ADD18MACRO18*%
%AMMACRO74*
4,1,8,.0034,.0082,
-.0034,.0082,
-.0082,.0034,
-.0082,-.00341,
-.00341,-.0082,
.0034,-.0082,
.0082,-.0034,
.0082,.0034,
.0034,.0082,
0.0*
%
%ADD74MACRO74*%
%AMMACRO45*
4,1,28,-.00673,.0033,
-.00878,.00448,
-.01153,-.00029,
-.011817,-.000904,
-.011994,-.001558,
-.012054,-.002232,
-.011997,-.002907,
-.011823,-.003562,
-.011538,-.004176,
-.01115,-.004732,
-.010672,-.005212,
-.010118,-.005602,
-.01007,-.00563,
.00016,-.01154,
.000773,-.01183,
.001425,-.012013,
.002099,-.01208,
.002774,-.012029,
.003431,-.011861,
.004048,-.011582,
.004607,-.0112,
.005092,-.010726,
.005487,-.010176,
.00551,-.01013,
.00827,-.00536,
.00622,-.00418,
.01144,.00485,
-.00152,.01233,
-.00673,.0033,
0.0*
%
%ADD45MACRO45*%
%AMMACRO73*
4,1,8,.0082,-.0034,
.0082,.0034,
.0034,.0082,
-.00341,.0082,
-.0082,.00341,
-.0082,-.0034,
-.0034,-.0082,
.0034,-.0082,
.0082,-.0034,
0.0*
%
%ADD73MACRO73*%
%AMMACRO15*
4,1,28,-.00748,-.00051,
-.00984,-.00051,
-.00984,-.00602,
-.009782,-.006695,
-.009607,-.007349,
-.009321,-.007964,
-.008933,-.008519,
-.008455,-.008998,
-.0079,-.009388,
-.007287,-.009675,
-.006632,-.009851,
-.005958,-.00991,
-.00591,-.00991,
.00591,-.00991,
.006585,-.009859,
.007242,-.009691,
.007859,-.009411,
.008418,-.009029,
.008903,-.008555,
.009297,-.008005,
.00959,-.007394,
.009773,-.006742,
.00984,-.006068,
.00984,-.00602,
.00984,-.00051,
.00748,-.00051,
.00748,.00992,
-.00748,.00992,
-.00748,-.00051,
0.0*
%
%ADD15MACRO15*%
%AMMACRO17*
4,1,28,-.00051,.00748,
-.00051,.00984,
-.00602,.00984,
-.006695,.009782,
-.007349,.009607,
-.007964,.009321,
-.008519,.008933,
-.008998,.008455,
-.009388,.0079,
-.009675,.007287,
-.009851,.006632,
-.00991,.005958,
-.00991,.00591,
-.00991,-.00591,
-.009859,-.006585,
-.009691,-.007242,
-.009411,-.007859,
-.009029,-.008418,
-.008555,-.008903,
-.008005,-.009297,
-.007394,-.00959,
-.006742,-.009773,
-.006068,-.00984,
-.00602,-.00984,
-.00051,-.00984,
-.00051,-.00748,
.00992,-.00748,
.00992,.00748,
-.00051,.00748,
0.0*
%
%ADD17MACRO17*%
%ADD62R,.021X.01*%
%ADD65R,.01X.021*%
%ADD84R,.01X.022*%
%ADD61R,.021X.012*%
%ADD64R,.012X.021*%
%ADD80R,.061X.01*%
%ADD75R,.022X.04*%
%ADD67R,.02X.016*%
%ADD33R,.015X.012*%
%ADD21R,.05X.04*%
%ADD79R,.061X.012*%
%ADD35R,.02X.017*%
%ADD32R,.012X.015*%
%ADD26R,.04X.05*%
%ADD63R,.025X.013*%
%ADD54R,.02X.018*%
%ADD49R,.017X.02*%
%ADD99R,.053X.022*%
%AMMACRO94*
21,1,.016,.0041,0.0,0.0,135.*%
%ADD94MACRO94*%
%ADD86R,.018X.02*%
%ADD60R,.013X.025*%
%AMMACRO55*
21,1,.016,.0041,0.0,0.0,144.*%
%ADD55MACRO55*%
%ADD98R,.063X.04*%
%ADD95R,.05X.035*%
%ADD76R,.024X.042*%
%ADD58R,.04X.071*%
%ADD97R,.036X.032*%
%ADD87R,.063X.015*%
%ADD78R,.017X.024*%
%ADD69R,.032X.036*%
%ADD37R,.032X.028*%
%ADD93R,.04X.056*%
%ADD68R,.056X.014*%
%ADD20R,.028X.032*%
%ADD82R,.024X.046*%
%ADD48R,.054X.044*%
%ADD36C,.315*%
%ADD19R,.044X.054*%
%ADD83R,.017X.046*%
%ADD77R,.059X.014*%
%ADD70R,.025X.048*%
%AMMACRO53*
4,1,28,-.00674,-.00329,
-.00878,-.00447,
-.01154,.0003,
-.011824,.000916,
-.012,.00157,
-.012059,.002245,
-.012001,.00292,
-.011826,.003574,
-.011541,.004188,
-.011153,.004744,
-.010674,.005223,
-.010119,.005612,
-.01008,.00564,
.00016,.01155,
.000772,.01184,
.001425,.012022,
.002099,.012088,
.002775,.012036,
.003431,.011868,
.004048,.011588,
.004606,.011205,
.00509,.010731,
.005485,.01018,
.00551,.01014,
.00826,.00537,
.00622,.00419,
.01143,-.00484,
-.00152,-.01232,
-.00674,-.00329,
0.0*
%
%ADD53MACRO53*%
%AMMACRO44*
4,1,28,.00674,.00329,
.00878,.00447,
.01154,-.0003,
.011824,-.000916,
.012,-.00157,
.012059,-.002245,
.012001,-.00292,
.011826,-.003574,
.011541,-.004188,
.011153,-.004744,
.010674,-.005223,
.010119,-.005612,
.01008,-.00564,
-.00016,-.01155,
-.000772,-.01184,
-.001425,-.012022,
-.002099,-.012088,
-.002775,-.012036,
-.003431,-.011868,
-.004048,-.011588,
-.004606,-.011205,
-.00509,-.010731,
-.005485,-.01018,
-.00551,-.01014,
-.00826,-.00537,
-.00622,-.00419,
-.01143,.00484,
.00152,.01232,
.00674,.00329,
0.0*
%
%ADD44MACRO44*%
%ADD57R,.059X.048*%
%AMMACRO51*
4,1,28,.00622,-.00419,
.00826,-.00537,
.00551,-.01014,
.005121,-.010695,
.004643,-.011175,
.004089,-.011564,
.003475,-.011852,
.002821,-.012028,
.002146,-.012089,
.001471,-.012031,
.000817,-.011857,
.000202,-.011572,
.00016,-.01155,
-.01008,-.00564,
-.010637,-.005254,
-.011122,-.00478,
-.011516,-.00423,
-.01181,-.003619,
-.011992,-.002967,
-.012059,-.002293,
-.012008,-.001617,
-.01184,-.000961,
-.01156,-.000344,
-.01154,-.0003,
-.00878,.00447,
-.00674,.00329,
-.00152,.01232,
.01143,.00484,
.00622,-.00419,
0.0*
%
%ADD51MACRO51*%
%ADD43R,.174X.174*%
%AMMACRO52*
4,1,28,-.00622,-.00418,
-.00827,-.00536,
-.00551,-.01013,
-.005125,-.010687,
-.004647,-.011167,
-.004093,-.011556,
-.003479,-.011844,
-.002825,-.01202,
-.00215,-.01208,
-.001475,-.012022,
-.000821,-.011848,
-.000206,-.011562,
-.00016,-.01154,
.01007,-.00563,
.010629,-.005248,
.011114,-.004775,
.01151,-.004224,
.011803,-.003614,
.011987,-.002962,
.012054,-.002288,
.012003,-.001612,
.011836,-.000956,
.011557,-.000338,
.01153,-.00029,
.00878,.00448,
.00673,.0033,
.00152,.01233,
-.01144,.00485,
-.00622,-.00418,
0.0*
%
%ADD52MACRO52*%
%AMMACRO47*
4,1,28,.00622,.00418,
.00827,.00536,
.00551,.01013,
.005125,.010687,
.004647,.011167,
.004093,.011556,
.003479,.011844,
.002825,.01202,
.00215,.01208,
.001475,.012022,
.000821,.011848,
.000206,.011562,
.00016,.01154,
-.01007,.00563,
-.010629,.005248,
-.011114,.004775,
-.01151,.004224,
-.011803,.003614,
-.011987,.002962,
-.012054,.002288,
-.012003,.001612,
-.011836,.000956,
-.011557,.000338,
-.01153,.00029,
-.00878,-.00448,
-.00673,-.0033,
-.00152,-.01233,
.01144,-.00485,
.00622,.00418,
0.0*
%
%ADD47MACRO47*%
%AMMACRO23*
4,1,28,-.00052,-.00748,
-.00052,-.00984,
-.00603,-.00984,
-.006705,-.009782,
-.007359,-.009607,
-.007974,-.009321,
-.008529,-.008933,
-.009009,-.008455,
-.009398,-.0079,
-.009685,-.007286,
-.009861,-.006632,
-.00992,-.005957,
-.00992,-.00591,
-.00992,.00591,
-.009869,.006585,
-.009701,.007242,
-.009421,.007859,
-.009039,.008418,
-.008565,.008903,
-.008015,.009297,
-.007404,.009591,
-.006751,.009773,
-.006077,.00984,
-.00603,.00984,
-.00052,.00984,
-.00052,.00748,
.00991,.00748,
.00991,-.00748,
-.00052,-.00748,
0.0*
%
%ADD23MACRO23*%
%AMMACRO14*
4,1,28,.00748,-.00052,
.00984,-.00052,
.00984,-.00603,
.009782,-.006705,
.009607,-.007359,
.009321,-.007974,
.008933,-.008529,
.008455,-.009009,
.0079,-.009398,
.007286,-.009685,
.006632,-.009861,
.005957,-.00992,
.00591,-.00992,
-.00591,-.00992,
-.006585,-.009869,
-.007242,-.009701,
-.007859,-.009421,
-.008418,-.009039,
-.008903,-.008565,
-.009297,-.008015,
-.009591,-.007404,
-.009773,-.006751,
-.00984,-.006077,
-.00984,-.00603,
-.00984,-.00052,
-.00748,-.00052,
-.00748,.00991,
.00748,.00991,
.00748,-.00052,
0.0*
%
%ADD14MACRO14*%
%AMMACRO72*
4,1,8,-.0034,-.0082,
.0034,-.0082,
.0082,-.0034,
.0082,.00341,
.00341,.0082,
-.0034,.0082,
-.0082,.0034,
-.0082,-.0034,
-.0034,-.0082,
0.0*
%
%ADD72MACRO72*%
%AMMACRO71*
4,1,8,-.0082,.0034,
-.0082,-.0034,
-.0034,-.0082,
.00341,-.0082,
.0082,-.00341,
.0082,.0034,
.0034,.0082,
-.0034,.0082,
-.0082,.0034,
0.0*
%
%ADD71MACRO71*%
%AMMACRO50*
4,1,28,.00673,-.0033,
.00878,-.00448,
.01153,.00029,
.011817,.000904,
.011994,.001558,
.012054,.002232,
.011997,.002907,
.011823,.003562,
.011538,.004176,
.01115,.004732,
.010672,.005212,
.010118,.005602,
.01007,.00563,
-.00016,.01154,
-.000773,.01183,
-.001425,.012013,
-.002099,.01208,
-.002774,.012029,
-.003431,.011861,
-.004048,.011582,
-.004607,.0112,
-.005092,.010726,
-.005487,.010176,
-.00551,.01013,
-.00827,.00536,
-.00622,.00418,
-.01144,-.00485,
.00152,-.01233,
.00673,-.0033,
0.0*
%
%ADD50MACRO50*%
%AMMACRO22*
4,1,28,.00051,-.00748,
.00051,-.00984,
.00602,-.00984,
.006695,-.009782,
.007349,-.009607,
.007964,-.009321,
.008519,-.008933,
.008998,-.008455,
.009388,-.0079,
.009675,-.007287,
.009851,-.006632,
.00991,-.005958,
.00991,-.00591,
.00991,.00591,
.009859,.006585,
.009691,.007242,
.009411,.007859,
.009029,.008418,
.008555,.008903,
.008005,.009297,
.007394,.00959,
.006742,.009773,
.006068,.00984,
.00602,.00984,
.00051,.00984,
.00051,.00748,
-.00992,.00748,
-.00992,-.00748,
.00051,-.00748,
0.0*
%
%ADD22MACRO22*%
%AMMACRO13*
4,1,28,.00748,.00051,
.00984,.00051,
.00984,.00602,
.009782,.006695,
.009607,.007349,
.009321,.007964,
.008933,.008519,
.008455,.008998,
.0079,.009388,
.007287,.009675,
.006632,.009851,
.005958,.00991,
.00591,.00991,
-.00591,.00991,
-.006585,.009859,
-.007242,.009691,
-.007859,.009411,
-.008418,.009029,
-.008903,.008555,
-.009297,.008005,
-.00959,.007394,
-.009773,.006742,
-.00984,.006068,
-.00984,.00602,
-.00984,.00051,
-.00748,.00051,
-.00748,-.00992,
.00748,-.00992,
.00748,.00051,
0.0*
%
%ADD13MACRO13*%
%ADD100C,.006*%
G75*
%LPD*%
G75*
G54D100*
G01X-476840Y-884638D02*
Y2768362D01*
X5911000D01*
Y-884638D01*
X-476840D01*
G01X8000Y-625138D02*
Y-630138D01*
G01X6543Y-625138D02*
X9457D01*
G01X14367Y-630138D02*
X11833D01*
Y-625138D01*
X14367D01*
G01X13353Y-627555D02*
X11833D01*
G01X16933Y-625138D02*
Y-630138D01*
X19467D01*
G01X23300Y-630305D02*
X23173Y-630221D01*
Y-630055D01*
X23300Y-629971D01*
X23427Y-630055D01*
Y-630221D01*
X23300Y-630305D01*
G01Y-628055D02*
X23173Y-627971D01*
Y-627805D01*
X23300Y-627721D01*
X23427Y-627805D01*
Y-627971D01*
X23300Y-628055D01*
G01X28083Y-631805D02*
X27450Y-630971D01*
X27133Y-630138D01*
Y-626805D01*
X27450Y-625971D01*
X28083Y-625138D01*
G01X33500D02*
X32993Y-625305D01*
X32613Y-625721D01*
X32360Y-626221D01*
X32170Y-626888D01*
X32107Y-627638D01*
X32170Y-628388D01*
X32360Y-629055D01*
X32613Y-629555D01*
X32993Y-629971D01*
X33500Y-630138D01*
X34007Y-629971D01*
X34387Y-629555D01*
X34640Y-629055D01*
X34830Y-628388D01*
X34893Y-627638D01*
X34830Y-626888D01*
X34640Y-626221D01*
X34387Y-625721D01*
X34007Y-625305D01*
X33500Y-625138D01*
G01X37207Y-629138D02*
X37587Y-629721D01*
X38093Y-630055D01*
X38663Y-630138D01*
X39170Y-630055D01*
X39677Y-629638D01*
X39993Y-629138D01*
X40057Y-628638D01*
X39930Y-628055D01*
X39487Y-627638D01*
X39043Y-627471D01*
X38473D01*
G01X39043D02*
X39423Y-627221D01*
X39740Y-626805D01*
X39867Y-626305D01*
X39740Y-625805D01*
X39423Y-625388D01*
X38853Y-625138D01*
X38283Y-625221D01*
X37713Y-625555D01*
G01X44017Y-631805D02*
X44650Y-630971D01*
X44967Y-630138D01*
Y-626805D01*
X44650Y-625971D01*
X44017Y-625138D01*
G01X47407Y-629138D02*
X47787Y-629721D01*
X48293Y-630055D01*
X48863Y-630138D01*
X49370Y-630055D01*
X49877Y-629638D01*
X50193Y-629138D01*
X50257Y-628638D01*
X50130Y-628055D01*
X49687Y-627638D01*
X49243Y-627471D01*
X48673D01*
G01X49243D02*
X49623Y-627221D01*
X49940Y-626805D01*
X50067Y-626305D01*
X49940Y-625805D01*
X49623Y-625388D01*
X49053Y-625138D01*
X48483Y-625221D01*
X47913Y-625555D01*
G01X52697Y-625971D02*
X53077Y-625471D01*
X53520Y-625221D01*
X54027Y-625138D01*
X54660Y-625305D01*
X55103Y-625721D01*
X55230Y-626221D01*
X55167Y-626721D01*
X54913Y-627138D01*
X53647Y-627971D01*
X53077Y-628555D01*
X52697Y-629388D01*
X52570Y-630138D01*
X55230D01*
G01X58873D02*
X59000Y-629055D01*
X59190Y-628138D01*
X59443Y-627305D01*
X59760Y-626388D01*
X60267Y-625138D01*
X57733D01*
G01X63277Y-628471D02*
X64923D01*
G01X67997Y-625971D02*
X68377Y-625471D01*
X68820Y-625221D01*
X69327Y-625138D01*
X69960Y-625305D01*
X70403Y-625721D01*
X70530Y-626221D01*
X70467Y-626721D01*
X70213Y-627138D01*
X68947Y-627971D01*
X68377Y-628555D01*
X67997Y-629388D01*
X67870Y-630138D01*
X70530D01*
G01X72907Y-629138D02*
X73287Y-629721D01*
X73793Y-630055D01*
X74363Y-630138D01*
X74870Y-630055D01*
X75377Y-629638D01*
X75693Y-629138D01*
X75757Y-628638D01*
X75630Y-628055D01*
X75187Y-627638D01*
X74743Y-627471D01*
X74173D01*
G01X74743D02*
X75123Y-627221D01*
X75440Y-626805D01*
X75567Y-626305D01*
X75440Y-625805D01*
X75123Y-625388D01*
X74553Y-625138D01*
X73983Y-625221D01*
X73413Y-625555D01*
G01X80160Y-630138D02*
Y-625138D01*
X77817Y-628721D01*
X80983D01*
G01X83107Y-629388D02*
X83487Y-629805D01*
X83930Y-630055D01*
X84500Y-630138D01*
X85070Y-629971D01*
X85513Y-629638D01*
X85830Y-629055D01*
X85893Y-628388D01*
X85767Y-627721D01*
X85450Y-627305D01*
X85007Y-626971D01*
X84563Y-626888D01*
X84120Y-626971D01*
X83550Y-627305D01*
X83740Y-625138D01*
X85450D01*
G01X93497Y-630138D02*
Y-625138D01*
X95903D01*
G01X95017Y-627555D02*
X93497D01*
G01X98217Y-630138D02*
X99800Y-625138D01*
X101383Y-630138D01*
G01X100813Y-628388D02*
X98787D01*
G01X103570Y-630138D02*
X106230Y-625138D01*
G01X103570D02*
X106230Y-630138D01*
G01X110000Y-630305D02*
X109873Y-630221D01*
Y-630055D01*
X110000Y-629971D01*
X110127Y-630055D01*
Y-630221D01*
X110000Y-630305D01*
G01Y-628055D02*
X109873Y-627971D01*
Y-627805D01*
X110000Y-627721D01*
X110127Y-627805D01*
Y-627971D01*
X110000Y-628055D01*
G01X114783Y-631805D02*
X114150Y-630971D01*
X113833Y-630138D01*
Y-626805D01*
X114150Y-625971D01*
X114783Y-625138D01*
G01X120200D02*
X119693Y-625305D01*
X119313Y-625721D01*
X119060Y-626221D01*
X118870Y-626888D01*
X118807Y-627638D01*
X118870Y-628388D01*
X119060Y-629055D01*
X119313Y-629555D01*
X119693Y-629971D01*
X120200Y-630138D01*
X120707Y-629971D01*
X121087Y-629555D01*
X121340Y-629055D01*
X121530Y-628388D01*
X121593Y-627638D01*
X121530Y-626888D01*
X121340Y-626221D01*
X121087Y-625721D01*
X120707Y-625305D01*
X120200Y-625138D01*
G01X123907Y-629138D02*
X124287Y-629721D01*
X124793Y-630055D01*
X125363Y-630138D01*
X125870Y-630055D01*
X126377Y-629638D01*
X126693Y-629138D01*
X126757Y-628638D01*
X126630Y-628055D01*
X126187Y-627638D01*
X125743Y-627471D01*
X125173D01*
G01X125743D02*
X126123Y-627221D01*
X126440Y-626805D01*
X126567Y-626305D01*
X126440Y-625805D01*
X126123Y-625388D01*
X125553Y-625138D01*
X124983Y-625221D01*
X124413Y-625555D01*
G01X130717Y-631805D02*
X131350Y-630971D01*
X131667Y-630138D01*
Y-626805D01*
X131350Y-625971D01*
X130717Y-625138D01*
G01X134107Y-629138D02*
X134487Y-629721D01*
X134993Y-630055D01*
X135563Y-630138D01*
X136070Y-630055D01*
X136577Y-629638D01*
X136893Y-629138D01*
X136957Y-628638D01*
X136830Y-628055D01*
X136387Y-627638D01*
X135943Y-627471D01*
X135373D01*
G01X135943D02*
X136323Y-627221D01*
X136640Y-626805D01*
X136767Y-626305D01*
X136640Y-625805D01*
X136323Y-625388D01*
X135753Y-625138D01*
X135183Y-625221D01*
X134613Y-625555D01*
G01X139523Y-629555D02*
X139967Y-629971D01*
X140473Y-630138D01*
X140980Y-629971D01*
X141423Y-629471D01*
X141740Y-628721D01*
X141867Y-627971D01*
Y-627055D01*
X141740Y-626305D01*
X141423Y-625638D01*
X141043Y-625305D01*
X140600Y-625138D01*
X140093Y-625305D01*
X139713Y-625638D01*
X139460Y-626138D01*
X139333Y-626805D01*
X139460Y-627388D01*
X139777Y-627971D01*
X140157Y-628305D01*
X140600Y-628388D01*
X141107Y-628221D01*
X141487Y-627805D01*
X141867Y-627055D01*
G01X145573Y-630138D02*
X145700Y-629055D01*
X145890Y-628138D01*
X146143Y-627305D01*
X146460Y-626388D01*
X146967Y-625138D01*
X144433D01*
G01X149977Y-628471D02*
X151623D01*
G01X154507Y-629138D02*
X154887Y-629721D01*
X155393Y-630055D01*
X155963Y-630138D01*
X156470Y-630055D01*
X156977Y-629638D01*
X157293Y-629138D01*
X157357Y-628638D01*
X157230Y-628055D01*
X156787Y-627638D01*
X156343Y-627471D01*
X155773D01*
G01X156343D02*
X156723Y-627221D01*
X157040Y-626805D01*
X157167Y-626305D01*
X157040Y-625805D01*
X156723Y-625388D01*
X156153Y-625138D01*
X155583Y-625221D01*
X155013Y-625555D01*
G01X159797Y-628055D02*
X160240Y-627471D01*
X160620Y-627138D01*
X161127Y-626971D01*
X161570Y-627138D01*
X161887Y-627471D01*
X162140Y-627971D01*
X162203Y-628555D01*
X162140Y-629055D01*
X161887Y-629555D01*
X161507Y-629971D01*
X161063Y-630138D01*
X160557Y-629971D01*
X160113Y-629471D01*
X159860Y-628721D01*
X159797Y-627888D01*
X159923Y-626805D01*
X160113Y-626221D01*
X160430Y-625638D01*
X160873Y-625221D01*
X161317Y-625138D01*
X161760Y-625305D01*
X162077Y-625721D01*
G01X166100Y-630138D02*
Y-625138D01*
X165340Y-626138D01*
G01Y-630138D02*
X166860D01*
G01X171960D02*
Y-625138D01*
X169617Y-628721D01*
X172783D01*
G01X-4000Y-560138D02*
Y-635138D01*
X496000D01*
Y-560138D01*
X-4000D01*
G01X191000D02*
Y-635138D01*
G01Y-610138D02*
X294000D01*
Y-585138D01*
G01X191000D02*
X294000D01*
G01X296000Y-560138D02*
Y-635138D01*
G01X294000Y-560138D02*
Y-635138D01*
G01X301507Y-620138D02*
Y-615138D01*
X302773D01*
X303280Y-615388D01*
X303660Y-615721D01*
X303977Y-616221D01*
X304230Y-616805D01*
X304293Y-617638D01*
X304230Y-618471D01*
X303977Y-619055D01*
X303660Y-619555D01*
X303280Y-619888D01*
X302773Y-620138D01*
X301507D01*
G01X306417D02*
X308000Y-615138D01*
X309583Y-620138D01*
G01X309013Y-618388D02*
X306987D01*
G01X313100Y-615138D02*
Y-620138D01*
G01X311643Y-615138D02*
X314557D01*
G01X319467Y-620138D02*
X316933D01*
Y-615138D01*
X319467D01*
G01X318453Y-617555D02*
X316933D01*
G01X323300Y-620305D02*
X323173Y-620221D01*
Y-620055D01*
X323300Y-619971D01*
X323427Y-620055D01*
Y-620221D01*
X323300Y-620305D01*
G01Y-618055D02*
X323173Y-617971D01*
Y-617805D01*
X323300Y-617721D01*
X323427Y-617805D01*
Y-617971D01*
X323300Y-618055D01*
G01X296000Y-610138D02*
X496000D01*
G01X301633Y-595138D02*
Y-590138D01*
X303153D01*
X303660Y-590388D01*
X304040Y-590971D01*
X304167Y-591638D01*
X304040Y-592305D01*
X303723Y-592805D01*
X303153Y-593055D01*
X301633D01*
G01X306860Y-595305D02*
X309140Y-590138D01*
G01X311643Y-595138D02*
Y-590138D01*
X314557Y-595138D01*
Y-590138D01*
G01X318200Y-595305D02*
X318073Y-595221D01*
Y-595055D01*
X318200Y-594971D01*
X318327Y-595055D01*
Y-595221D01*
X318200Y-595305D01*
G01Y-593055D02*
X318073Y-592971D01*
Y-592805D01*
X318200Y-592721D01*
X318327Y-592805D01*
Y-592971D01*
X318200Y-593055D01*
G01X296000Y-585138D02*
X496000D01*
G01X301633Y-570138D02*
Y-565138D01*
X303153D01*
X303660Y-565388D01*
X304040Y-565971D01*
X304167Y-566638D01*
X304040Y-567305D01*
X303723Y-567805D01*
X303153Y-568055D01*
X301633D01*
G01X306733Y-570138D02*
Y-565138D01*
X308317D01*
X308823Y-565388D01*
X309140Y-565721D01*
X309267Y-566388D01*
X309140Y-567055D01*
X308760Y-567471D01*
X308317Y-567721D01*
X306733D01*
G01X308317D02*
X309267Y-570138D01*
G01X313100D02*
X312593Y-570055D01*
X312150Y-569721D01*
X311770Y-569221D01*
X311517Y-568638D01*
X311390Y-567971D01*
Y-567305D01*
X311517Y-566638D01*
X311770Y-566055D01*
X312150Y-565555D01*
X312593Y-565221D01*
X313100Y-565138D01*
X313607Y-565221D01*
X314050Y-565555D01*
X314430Y-566055D01*
X314683Y-566638D01*
X314810Y-567305D01*
Y-567971D01*
X314683Y-568638D01*
X314430Y-569221D01*
X314050Y-569721D01*
X313607Y-570055D01*
X313100Y-570138D01*
G01X316933Y-569138D02*
X317250Y-569638D01*
X317630Y-569971D01*
X318073Y-570138D01*
X318580Y-569971D01*
X318960Y-569638D01*
X319340Y-569138D01*
X319467Y-568471D01*
Y-565138D01*
G01X324567Y-570138D02*
X322033D01*
Y-565138D01*
X324567D01*
G01X323553Y-567555D02*
X322033D01*
G01X329793Y-565555D02*
X329413Y-565305D01*
X328970Y-565138D01*
X328463D01*
X327893Y-565388D01*
X327450Y-565805D01*
X327133Y-566305D01*
X326880Y-567138D01*
X326817Y-567888D01*
X326943Y-568638D01*
X327133Y-569138D01*
X327513Y-569638D01*
X327957Y-569971D01*
X328400Y-570138D01*
X328843D01*
X329287Y-569971D01*
X329667Y-569721D01*
X329983Y-569388D01*
G01X333500Y-565138D02*
Y-570138D01*
G01X332043Y-565138D02*
X334957D01*
G01X338600Y-570305D02*
X338473Y-570221D01*
Y-570055D01*
X338600Y-569971D01*
X338727Y-570055D01*
Y-570221D01*
X338600Y-570305D01*
G01Y-568055D02*
X338473Y-567971D01*
Y-567805D01*
X338600Y-567721D01*
X338727Y-567805D01*
Y-567971D01*
X338600Y-568055D01*
G01X411000Y-610138D02*
Y-635138D01*
G01X413633Y-612638D02*
Y-617638D01*
X416167D01*
G01X419240Y-612638D02*
X420760D01*
G01X420000D02*
Y-617638D01*
G01X419240D02*
X420760D01*
G01X425607Y-614971D02*
X425860Y-614721D01*
X426050Y-614305D01*
X426177Y-613721D01*
X426050Y-613221D01*
X425797Y-612888D01*
X425353Y-612638D01*
X423643D01*
Y-617638D01*
X425733D01*
X426177Y-617305D01*
X426430Y-616805D01*
X426557Y-616221D01*
X426430Y-615638D01*
X426050Y-615138D01*
X425607Y-614971D01*
X423643D01*
G01X430200Y-617805D02*
X430073Y-617721D01*
Y-617555D01*
X430200Y-617471D01*
X430327Y-617555D01*
Y-617721D01*
X430200Y-617805D01*
G01Y-615555D02*
X430073Y-615471D01*
Y-615305D01*
X430200Y-615221D01*
X430327Y-615305D01*
Y-615471D01*
X430200Y-615555D01*
G01X454000Y-610138D02*
Y-635138D01*
G01Y-585138D02*
Y-610138D01*
G01X459013Y-637305D02*
X459120Y-637180D01*
X459200Y-636971D01*
X459253Y-636680D01*
X459200Y-636430D01*
X459093Y-636263D01*
X458907Y-636138D01*
X458187D01*
Y-638638D01*
X459067D01*
X459253Y-638471D01*
X459360Y-638221D01*
X459413Y-637930D01*
X459360Y-637638D01*
X459200Y-637388D01*
X459013Y-637305D01*
X458187D01*
G01X461480Y-638638D02*
Y-636971D01*
G01Y-637263D02*
X461373Y-637096D01*
X461213Y-637013D01*
X461027Y-636971D01*
X460840Y-637055D01*
X460680Y-637221D01*
X460573Y-637471D01*
X460520Y-637805D01*
X460573Y-638138D01*
X460680Y-638388D01*
X460840Y-638555D01*
X461027Y-638638D01*
X461213Y-638596D01*
X461373Y-638471D01*
X461480Y-638305D01*
G01X462800Y-638346D02*
X462933Y-638513D01*
X463120Y-638638D01*
X463280D01*
X463440Y-638555D01*
X463547Y-638430D01*
X463600Y-638263D01*
X463573Y-638013D01*
X463467Y-637888D01*
X462987Y-637638D01*
X462880Y-637346D01*
X462933Y-637138D01*
X463040Y-637013D01*
X463200Y-636971D01*
X463360Y-637013D01*
X463520Y-637138D01*
G01X465000Y-637513D02*
X465853D01*
X465773Y-637221D01*
X465640Y-637055D01*
X465453Y-636971D01*
X465267Y-637013D01*
X465107Y-637138D01*
X465000Y-637430D01*
X464947Y-637680D01*
Y-637930D01*
X465000Y-638180D01*
X465133Y-638430D01*
X465293Y-638596D01*
X465480Y-638638D01*
X465667Y-638555D01*
X465853Y-638305D01*
G01X467120Y-638638D02*
Y-636138D01*
G01Y-637388D02*
X467253Y-637138D01*
X467413Y-637013D01*
X467573Y-636971D01*
X467813Y-637055D01*
X467973Y-637221D01*
X468080Y-637513D01*
Y-637846D01*
X468027Y-638180D01*
X467920Y-638430D01*
X467733Y-638596D01*
X467573Y-638638D01*
X467413Y-638596D01*
X467253Y-638471D01*
X467120Y-638263D01*
G01X469800Y-638638D02*
X469640Y-638596D01*
X469480Y-638430D01*
X469373Y-638138D01*
X469320Y-637805D01*
X469373Y-637471D01*
X469480Y-637180D01*
X469640Y-637013D01*
X469800Y-636971D01*
X469960Y-637013D01*
X470120Y-637180D01*
X470227Y-637471D01*
X470253Y-637805D01*
X470227Y-638138D01*
X470120Y-638430D01*
X469960Y-638596D01*
X469800Y-638638D01*
G01X472480D02*
Y-636971D01*
G01Y-637263D02*
X472373Y-637096D01*
X472213Y-637013D01*
X472027Y-636971D01*
X471840Y-637055D01*
X471680Y-637221D01*
X471573Y-637471D01*
X471520Y-637805D01*
X471573Y-638138D01*
X471680Y-638388D01*
X471840Y-638555D01*
X472027Y-638638D01*
X472213Y-638596D01*
X472373Y-638471D01*
X472480Y-638305D01*
G01X473827Y-638638D02*
Y-636971D01*
G01Y-637305D02*
X473960Y-637138D01*
X474093Y-637013D01*
X474280Y-636971D01*
X474413Y-637013D01*
X474573Y-637138D01*
G01X476880Y-636138D02*
Y-638638D01*
G01Y-638263D02*
X476773Y-638471D01*
X476613Y-638596D01*
X476427Y-638638D01*
X476213Y-638555D01*
X476053Y-638346D01*
X475947Y-638096D01*
X475920Y-637805D01*
X475947Y-637513D01*
X476053Y-637263D01*
X476213Y-637055D01*
X476427Y-636971D01*
X476613Y-637013D01*
X476747Y-637096D01*
X476880Y-637263D01*
G01X480267Y-638638D02*
Y-636138D01*
X480933D01*
X481147Y-636263D01*
X481280Y-636430D01*
X481333Y-636763D01*
X481280Y-637096D01*
X481120Y-637305D01*
X480933Y-637430D01*
X480267D01*
G01X480933D02*
X481333Y-638638D01*
G01X482600Y-637513D02*
X483453D01*
X483373Y-637221D01*
X483240Y-637055D01*
X483053Y-636971D01*
X482867Y-637013D01*
X482707Y-637138D01*
X482600Y-637430D01*
X482547Y-637680D01*
Y-637930D01*
X482600Y-638180D01*
X482733Y-638430D01*
X482893Y-638596D01*
X483080Y-638638D01*
X483267Y-638555D01*
X483453Y-638305D01*
G01X484720Y-636971D02*
X485200Y-638638D01*
X485680Y-636971D01*
G01X487400Y-638721D02*
X487347Y-638680D01*
Y-638596D01*
X487400Y-638555D01*
X487453Y-638596D01*
Y-638680D01*
X487400Y-638721D01*
G01X489147Y-638346D02*
X489333Y-638555D01*
X489547Y-638638D01*
X489760Y-638555D01*
X489947Y-638305D01*
X490080Y-637930D01*
X490133Y-637555D01*
Y-637096D01*
X490080Y-636721D01*
X489947Y-636388D01*
X489787Y-636221D01*
X489600Y-636138D01*
X489387Y-636221D01*
X489227Y-636388D01*
X489120Y-636638D01*
X489067Y-636971D01*
X489120Y-637263D01*
X489253Y-637555D01*
X489413Y-637721D01*
X489600Y-637763D01*
X489813Y-637680D01*
X489973Y-637471D01*
X490133Y-637096D01*
G01X492013Y-637305D02*
X492120Y-637180D01*
X492200Y-636971D01*
X492253Y-636680D01*
X492200Y-636430D01*
X492093Y-636263D01*
X491907Y-636138D01*
X491187D01*
Y-638638D01*
X492067D01*
X492253Y-638471D01*
X492360Y-638221D01*
X492413Y-637930D01*
X492360Y-637638D01*
X492200Y-637388D01*
X492013Y-637305D01*
X491187D01*
G01X457900Y-612638D02*
Y-617638D01*
G01X456443Y-612638D02*
X459357D01*
G01X463000Y-617638D02*
X462620Y-617555D01*
X462240Y-617221D01*
X461987Y-616638D01*
X461860Y-615971D01*
X461987Y-615305D01*
X462240Y-614721D01*
X462620Y-614388D01*
X463000Y-614305D01*
X463380Y-614388D01*
X463760Y-614721D01*
X464013Y-615305D01*
X464077Y-615971D01*
X464013Y-616638D01*
X463760Y-617221D01*
X463380Y-617555D01*
X463000Y-617638D01*
G01X468100D02*
X467720Y-617555D01*
X467340Y-617221D01*
X467087Y-616638D01*
X466960Y-615971D01*
X467087Y-615305D01*
X467340Y-614721D01*
X467720Y-614388D01*
X468100Y-614305D01*
X468480Y-614388D01*
X468860Y-614721D01*
X469113Y-615305D01*
X469177Y-615971D01*
X469113Y-616638D01*
X468860Y-617221D01*
X468480Y-617555D01*
X468100Y-617638D01*
G01X473200D02*
Y-612638D01*
G01X478300Y-617805D02*
X478173Y-617721D01*
Y-617555D01*
X478300Y-617471D01*
X478427Y-617555D01*
Y-617721D01*
X478300Y-617805D01*
G01Y-615555D02*
X478173Y-615471D01*
Y-615305D01*
X478300Y-615221D01*
X478427Y-615305D01*
Y-615471D01*
X478300Y-615555D01*
G01X456633Y-592638D02*
Y-587638D01*
X458217D01*
X458723Y-587888D01*
X459040Y-588221D01*
X459167Y-588888D01*
X459040Y-589555D01*
X458660Y-589971D01*
X458217Y-590221D01*
X456633D01*
G01X458217D02*
X459167Y-592638D01*
G01X464267D02*
X461733D01*
Y-587638D01*
X464267D01*
G01X463253Y-590055D02*
X461733D01*
G01X466517Y-587638D02*
X468100Y-592638D01*
X469683Y-587638D01*
G01X473200Y-592805D02*
X473073Y-592721D01*
Y-592555D01*
X473200Y-592471D01*
X473327Y-592555D01*
Y-592721D01*
X473200Y-592805D01*
G01Y-590555D02*
X473073Y-590471D01*
Y-590305D01*
X473200Y-590221D01*
X473327Y-590305D01*
Y-590471D01*
X473200Y-590555D01*
G01X-476840Y-884638D02*
Y2768362D01*
X5911000D01*
Y-884638D01*
X-476840D01*
G01X8820Y-607488D02*
X10387D01*
Y-609378D01*
X9917Y-610008D01*
X9368Y-610428D01*
X8585Y-610638D01*
X7802Y-610428D01*
X7253Y-610008D01*
X6783Y-609378D01*
X6470Y-608643D01*
X6313Y-607803D01*
Y-607068D01*
X6470Y-606438D01*
X6783Y-605703D01*
X7253Y-605073D01*
X7723Y-604653D01*
X8350Y-604338D01*
X8898D01*
X9525Y-604548D01*
X9995Y-604968D01*
G01X12927Y-604338D02*
Y-608853D01*
X13240Y-609798D01*
X13867Y-610428D01*
X14650Y-610638D01*
X15433Y-610428D01*
X16060Y-609798D01*
X16373Y-608853D01*
Y-604338D01*
G01X20010D02*
X21890D01*
G01X20950D02*
Y-610638D01*
G01X20010D02*
X21890D01*
G01X25605Y-609798D02*
X26232Y-610323D01*
X26937Y-610638D01*
X27563D01*
X28190Y-610323D01*
X28660Y-609798D01*
X28895Y-609063D01*
X28738Y-608328D01*
X28347Y-607698D01*
X27642Y-607278D01*
X26702Y-607068D01*
X26153Y-606648D01*
X25918Y-605913D01*
X26075Y-605178D01*
X26467Y-604653D01*
X27015Y-604338D01*
X27563D01*
X28112Y-604548D01*
X28582Y-605073D01*
G01X31905Y-610638D02*
Y-604338D01*
G01X35195D02*
Y-610638D01*
G01Y-607488D02*
X31905D01*
G01X37892Y-610638D02*
X39850Y-604338D01*
X41808Y-610638D01*
G01X41103Y-608433D02*
X38597D01*
G01X44348Y-610638D02*
Y-604338D01*
X47952Y-610638D01*
Y-604338D01*
G01X57027Y-610638D02*
Y-604338D01*
X58593D01*
X59220Y-604653D01*
X59690Y-605073D01*
X60082Y-605703D01*
X60395Y-606438D01*
X60473Y-607488D01*
X60395Y-608538D01*
X60082Y-609273D01*
X59690Y-609903D01*
X59220Y-610323D01*
X58593Y-610638D01*
X57027D01*
G01X64110Y-604338D02*
X65990D01*
G01X65050D02*
Y-610638D01*
G01X64110D02*
X65990D01*
G01X69705Y-609798D02*
X70332Y-610323D01*
X71037Y-610638D01*
X71663D01*
X72290Y-610323D01*
X72760Y-609798D01*
X72995Y-609063D01*
X72838Y-608328D01*
X72447Y-607698D01*
X71742Y-607278D01*
X70802Y-607068D01*
X70253Y-606648D01*
X70018Y-605913D01*
X70175Y-605178D01*
X70567Y-604653D01*
X71115Y-604338D01*
X71663D01*
X72212Y-604548D01*
X72682Y-605073D01*
G01X77650Y-604338D02*
Y-610638D01*
G01X75848Y-604338D02*
X79452D01*
G01X83950Y-610848D02*
X83793Y-610743D01*
Y-610533D01*
X83950Y-610428D01*
X84107Y-610533D01*
Y-610743D01*
X83950Y-610848D01*
G01X90093Y-611793D02*
X90407Y-610428D01*
G01X96550Y-604338D02*
Y-610638D01*
G01X94748Y-604338D02*
X98352D01*
G01X100892Y-610638D02*
X102850Y-604338D01*
X104808Y-610638D01*
G01X104103Y-608433D02*
X101597D01*
G01X109150Y-610638D02*
X108523Y-610533D01*
X107975Y-610113D01*
X107505Y-609483D01*
X107192Y-608748D01*
X107035Y-607908D01*
Y-607068D01*
X107192Y-606228D01*
X107505Y-605493D01*
X107975Y-604863D01*
X108523Y-604443D01*
X109150Y-604338D01*
X109777Y-604443D01*
X110325Y-604863D01*
X110795Y-605493D01*
X111108Y-606228D01*
X111265Y-607068D01*
Y-607908D01*
X111108Y-608748D01*
X110795Y-609483D01*
X110325Y-610113D01*
X109777Y-610533D01*
X109150Y-610638D01*
G01X115450D02*
Y-607803D01*
X113883Y-604338D01*
G01X117017D02*
X115450Y-607803D01*
G01X120027Y-604338D02*
Y-608853D01*
X120340Y-609798D01*
X120967Y-610428D01*
X121750Y-610638D01*
X122533Y-610428D01*
X123160Y-609798D01*
X123473Y-608853D01*
Y-604338D01*
G01X126092Y-610638D02*
X128050Y-604338D01*
X130008Y-610638D01*
G01X129303Y-608433D02*
X126797D01*
G01X132548Y-610638D02*
Y-604338D01*
X136152Y-610638D01*
Y-604338D01*
G01X10073Y-614863D02*
X9603Y-614548D01*
X9055Y-614338D01*
X8428D01*
X7723Y-614653D01*
X7175Y-615178D01*
X6783Y-615808D01*
X6470Y-616858D01*
X6392Y-617803D01*
X6548Y-618748D01*
X6783Y-619378D01*
X7253Y-620008D01*
X7802Y-620428D01*
X8350Y-620638D01*
X8898D01*
X9447Y-620428D01*
X9917Y-620113D01*
X10308Y-619693D01*
G01X13710Y-614338D02*
X15590D01*
G01X14650D02*
Y-620638D01*
G01X13710D02*
X15590D01*
G01X20950Y-614338D02*
Y-620638D01*
G01X19148Y-614338D02*
X22752D01*
G01X27250Y-620638D02*
Y-617803D01*
X25683Y-614338D01*
G01X28817D02*
X27250Y-617803D01*
G01X38127Y-619378D02*
X38597Y-620113D01*
X39223Y-620533D01*
X39928Y-620638D01*
X40555Y-620533D01*
X41182Y-620008D01*
X41573Y-619378D01*
X41652Y-618748D01*
X41495Y-618013D01*
X40947Y-617488D01*
X40398Y-617278D01*
X39693D01*
G01X40398D02*
X40868Y-616963D01*
X41260Y-616438D01*
X41417Y-615808D01*
X41260Y-615178D01*
X40868Y-614653D01*
X40163Y-614338D01*
X39458Y-614443D01*
X38753Y-614863D01*
G01X44427Y-619378D02*
X44897Y-620113D01*
X45523Y-620533D01*
X46228Y-620638D01*
X46855Y-620533D01*
X47482Y-620008D01*
X47873Y-619378D01*
X47952Y-618748D01*
X47795Y-618013D01*
X47247Y-617488D01*
X46698Y-617278D01*
X45993D01*
G01X46698D02*
X47168Y-616963D01*
X47560Y-616438D01*
X47717Y-615808D01*
X47560Y-615178D01*
X47168Y-614653D01*
X46463Y-614338D01*
X45758Y-614443D01*
X45053Y-614863D01*
G01X50727Y-619378D02*
X51197Y-620113D01*
X51823Y-620533D01*
X52528Y-620638D01*
X53155Y-620533D01*
X53782Y-620008D01*
X54173Y-619378D01*
X54252Y-618748D01*
X54095Y-618013D01*
X53547Y-617488D01*
X52998Y-617278D01*
X52293D01*
G01X52998D02*
X53468Y-616963D01*
X53860Y-616438D01*
X54017Y-615808D01*
X53860Y-615178D01*
X53468Y-614653D01*
X52763Y-614338D01*
X52058Y-614443D01*
X51353Y-614863D01*
G01X58593Y-620638D02*
X58750Y-619273D01*
X58985Y-618118D01*
X59298Y-617068D01*
X59690Y-615913D01*
X60317Y-614338D01*
X57183D01*
G01X64893Y-620638D02*
X65050Y-619273D01*
X65285Y-618118D01*
X65598Y-617068D01*
X65990Y-615913D01*
X66617Y-614338D01*
X63483D01*
G01X71193Y-621793D02*
X71507Y-620428D01*
G01X77650Y-614338D02*
Y-620638D01*
G01X75848Y-614338D02*
X79452D01*
G01X81992Y-620638D02*
X83950Y-614338D01*
X85908Y-620638D01*
G01X85203Y-618433D02*
X82697D01*
G01X89310Y-614338D02*
X91190D01*
G01X90250D02*
Y-620638D01*
G01X89310D02*
X91190D01*
G01X94200Y-614338D02*
X95297Y-620638D01*
X96550Y-614338D01*
X97803Y-620638D01*
X98900Y-614338D01*
G01X100892Y-620638D02*
X102850Y-614338D01*
X104808Y-620638D01*
G01X104103Y-618433D02*
X101597D01*
G01X107348Y-620638D02*
Y-614338D01*
X110952Y-620638D01*
Y-614338D01*
G01X121358Y-622738D02*
X120575Y-621688D01*
X120183Y-620638D01*
Y-616438D01*
X120575Y-615388D01*
X121358Y-614338D01*
G01X132783Y-620638D02*
Y-614338D01*
X134742D01*
X135368Y-614653D01*
X135760Y-615073D01*
X135917Y-615913D01*
X135760Y-616753D01*
X135290Y-617278D01*
X134742Y-617593D01*
X132783D01*
G01X134742D02*
X135917Y-620638D01*
G01X140650Y-620848D02*
X140493Y-620743D01*
Y-620533D01*
X140650Y-620428D01*
X140807Y-620533D01*
Y-620743D01*
X140650Y-620848D01*
G01X146950Y-620638D02*
X146323Y-620533D01*
X145775Y-620113D01*
X145305Y-619483D01*
X144992Y-618748D01*
X144835Y-617908D01*
Y-617068D01*
X144992Y-616228D01*
X145305Y-615493D01*
X145775Y-614863D01*
X146323Y-614443D01*
X146950Y-614338D01*
X147577Y-614443D01*
X148125Y-614863D01*
X148595Y-615493D01*
X148908Y-616228D01*
X149065Y-617068D01*
Y-617908D01*
X148908Y-618748D01*
X148595Y-619483D01*
X148125Y-620113D01*
X147577Y-620533D01*
X146950Y-620638D01*
G01X153250Y-620848D02*
X153093Y-620743D01*
Y-620533D01*
X153250Y-620428D01*
X153407Y-620533D01*
Y-620743D01*
X153250Y-620848D01*
G01X161273Y-614863D02*
X160803Y-614548D01*
X160255Y-614338D01*
X159628D01*
X158923Y-614653D01*
X158375Y-615178D01*
X157983Y-615808D01*
X157670Y-616858D01*
X157592Y-617803D01*
X157748Y-618748D01*
X157983Y-619378D01*
X158453Y-620008D01*
X159002Y-620428D01*
X159550Y-620638D01*
X160098D01*
X160647Y-620428D01*
X161117Y-620113D01*
X161508Y-619693D01*
G01X165850Y-620848D02*
X165693Y-620743D01*
Y-620533D01*
X165850Y-620428D01*
X166007Y-620533D01*
Y-620743D01*
X165850Y-620848D01*
G01X172542Y-622738D02*
X173325Y-621688D01*
X173717Y-620638D01*
Y-616438D01*
X173325Y-615388D01*
X172542Y-614338D01*
G01X6548Y-600638D02*
Y-594338D01*
X10152Y-600638D01*
Y-594338D01*
G01X14650Y-600638D02*
X14023Y-600533D01*
X13475Y-600113D01*
X13005Y-599483D01*
X12692Y-598748D01*
X12535Y-597908D01*
Y-597068D01*
X12692Y-596228D01*
X13005Y-595493D01*
X13475Y-594863D01*
X14023Y-594443D01*
X14650Y-594338D01*
X15277Y-594443D01*
X15825Y-594863D01*
X16295Y-595493D01*
X16608Y-596228D01*
X16765Y-597068D01*
Y-597908D01*
X16608Y-598748D01*
X16295Y-599483D01*
X15825Y-600113D01*
X15277Y-600533D01*
X14650Y-600638D01*
G01X20950Y-600848D02*
X20793Y-600743D01*
Y-600533D01*
X20950Y-600428D01*
X21107Y-600533D01*
Y-600743D01*
X20950Y-600848D01*
G01X25762Y-595388D02*
X26232Y-594758D01*
X26780Y-594443D01*
X27407Y-594338D01*
X28190Y-594548D01*
X28738Y-595073D01*
X28895Y-595703D01*
X28817Y-596333D01*
X28503Y-596858D01*
X26937Y-597908D01*
X26232Y-598643D01*
X25762Y-599693D01*
X25605Y-600638D01*
X28895D01*
G01X33550D02*
Y-594338D01*
X32610Y-595598D01*
G01Y-600638D02*
X34490D01*
G01X39850D02*
Y-594338D01*
X38910Y-595598D01*
G01Y-600638D02*
X40790D01*
G01X45993Y-601793D02*
X46307Y-600428D01*
G01X50100Y-594338D02*
X51197Y-600638D01*
X52450Y-594338D01*
X53703Y-600638D01*
X54800Y-594338D01*
G01X60317Y-600638D02*
X57183D01*
Y-594338D01*
X60317D01*
G01X59063Y-597383D02*
X57183D01*
G01X63248Y-600638D02*
Y-594338D01*
X66852Y-600638D01*
Y-594338D01*
G01X69705Y-600638D02*
Y-594338D01*
G01X72995D02*
Y-600638D01*
G01Y-597488D02*
X69705D01*
G01X75927Y-594338D02*
Y-598853D01*
X76240Y-599798D01*
X76867Y-600428D01*
X77650Y-600638D01*
X78433Y-600428D01*
X79060Y-599798D01*
X79373Y-598853D01*
Y-594338D01*
G01X81992Y-600638D02*
X83950Y-594338D01*
X85908Y-600638D01*
G01X85203Y-598433D02*
X82697D01*
G01X95062Y-595388D02*
X95532Y-594758D01*
X96080Y-594443D01*
X96707Y-594338D01*
X97490Y-594548D01*
X98038Y-595073D01*
X98195Y-595703D01*
X98117Y-596333D01*
X97803Y-596858D01*
X96237Y-597908D01*
X95532Y-598643D01*
X95062Y-599693D01*
X94905Y-600638D01*
X98195D01*
G01X101048D02*
Y-594338D01*
X104652Y-600638D01*
Y-594338D01*
G01X107427Y-600638D02*
Y-594338D01*
X108993D01*
X109620Y-594653D01*
X110090Y-595073D01*
X110482Y-595703D01*
X110795Y-596438D01*
X110873Y-597488D01*
X110795Y-598538D01*
X110482Y-599273D01*
X110090Y-599903D01*
X109620Y-600323D01*
X108993Y-600638D01*
X107427D01*
G01X120183D02*
Y-594338D01*
X122142D01*
X122768Y-594653D01*
X123160Y-595073D01*
X123317Y-595913D01*
X123160Y-596753D01*
X122690Y-597278D01*
X122142Y-597593D01*
X120183D01*
G01X122142D02*
X123317Y-600638D01*
G01X126327D02*
Y-594338D01*
X127893D01*
X128520Y-594653D01*
X128990Y-595073D01*
X129382Y-595703D01*
X129695Y-596438D01*
X129773Y-597488D01*
X129695Y-598538D01*
X129382Y-599273D01*
X128990Y-599903D01*
X128520Y-600323D01*
X127893Y-600638D01*
X126327D01*
G01X134350Y-600848D02*
X134193Y-600743D01*
Y-600533D01*
X134350Y-600428D01*
X134507Y-600533D01*
Y-600743D01*
X134350Y-600848D01*
G01X30650Y-589938D02*
X28130Y-589521D01*
X25925Y-587855D01*
X24035Y-585355D01*
X22775Y-582438D01*
X22145Y-579105D01*
Y-575771D01*
X22775Y-572438D01*
X24035Y-569521D01*
X25925Y-567022D01*
X28130Y-565355D01*
X30650Y-564938D01*
X33170Y-565355D01*
X35375Y-567022D01*
X37265Y-569521D01*
X38525Y-572438D01*
X39155Y-575771D01*
Y-579105D01*
X38525Y-582438D01*
X37265Y-585355D01*
X35375Y-587855D01*
X33170Y-589521D01*
X30650Y-589938D01*
G01X33170Y-583271D02*
X36950Y-589938D01*
G01X50495Y-573272D02*
Y-584938D01*
X51755Y-587855D01*
X53645Y-589521D01*
X55850Y-589938D01*
X58055Y-589521D01*
X59945Y-587855D01*
X61205Y-584938D01*
G01Y-589938D02*
Y-573272D01*
G01X86720Y-589938D02*
Y-573272D01*
G01Y-576188D02*
X85460Y-574522D01*
X83570Y-573688D01*
X81365Y-573272D01*
X79160Y-574105D01*
X77270Y-575771D01*
X76010Y-578272D01*
X75380Y-581605D01*
X76010Y-584938D01*
X77270Y-587439D01*
X79160Y-589105D01*
X81365Y-589938D01*
X83570Y-589521D01*
X85460Y-588272D01*
X86720Y-586605D01*
G01X100895Y-589938D02*
Y-573272D01*
G01Y-577438D02*
X102155Y-575355D01*
X104045Y-573688D01*
X106565Y-573272D01*
X108770Y-573688D01*
X110660Y-575355D01*
X111605Y-578272D01*
Y-589938D01*
G01X131450Y-564938D02*
Y-589938D01*
G01X127040Y-573272D02*
X135860D01*
G01X162320Y-589938D02*
Y-573272D01*
G01Y-576188D02*
X161060Y-574522D01*
X159170Y-573688D01*
X156965Y-573272D01*
X154760Y-574105D01*
X152870Y-575771D01*
X151610Y-578272D01*
X150980Y-581605D01*
X151610Y-584938D01*
X152870Y-587439D01*
X154760Y-589105D01*
X156965Y-589938D01*
X159170Y-589521D01*
X161060Y-588272D01*
X162320Y-586605D01*
G01X213500Y-602638D02*
Y-594638D01*
X215900D01*
X216700Y-595038D01*
X217300Y-595971D01*
X217500Y-597038D01*
X217300Y-598105D01*
X216800Y-598905D01*
X215900Y-599305D01*
X213500D01*
G01X221000Y-602638D02*
X223500Y-594638D01*
X226000Y-602638D01*
G01X225100Y-599838D02*
X221900D01*
G01X229400Y-601572D02*
X230200Y-602238D01*
X231100Y-602638D01*
X231900D01*
X232700Y-602238D01*
X233300Y-601572D01*
X233600Y-600638D01*
X233400Y-599705D01*
X232900Y-598905D01*
X232000Y-598371D01*
X230800Y-598105D01*
X230100Y-597571D01*
X229800Y-596638D01*
X230000Y-595705D01*
X230500Y-595038D01*
X231200Y-594638D01*
X231900D01*
X232600Y-594905D01*
X233200Y-595571D01*
G01X239500Y-594638D02*
Y-602638D01*
G01X237200Y-594638D02*
X241800D01*
G01X246200Y-599971D02*
X248800D01*
G01X256300Y-598371D02*
X256700Y-597971D01*
X257000Y-597305D01*
X257200Y-596371D01*
X257000Y-595571D01*
X256600Y-595038D01*
X255900Y-594638D01*
X253200D01*
Y-602638D01*
X256500D01*
X257200Y-602105D01*
X257600Y-601305D01*
X257800Y-600371D01*
X257600Y-599438D01*
X257000Y-598638D01*
X256300Y-598371D01*
X253200D01*
G01X263500Y-602638D02*
X262700Y-602505D01*
X262000Y-601971D01*
X261400Y-601171D01*
X261000Y-600238D01*
X260800Y-599171D01*
Y-598105D01*
X261000Y-597038D01*
X261400Y-596105D01*
X262000Y-595305D01*
X262700Y-594771D01*
X263500Y-594638D01*
X264300Y-594771D01*
X265000Y-595305D01*
X265600Y-596105D01*
X266000Y-597038D01*
X266200Y-598105D01*
Y-599171D01*
X266000Y-600238D01*
X265600Y-601171D01*
X265000Y-601971D01*
X264300Y-602505D01*
X263500Y-602638D01*
G01X271500Y-594638D02*
Y-602638D01*
G01X269200Y-594638D02*
X273800D01*
G01X202000Y-569638D02*
Y-577638D01*
X206000D01*
G01X213800D02*
Y-572305D01*
G01Y-573238D02*
X213400Y-572705D01*
X212800Y-572438D01*
X212100Y-572305D01*
X211400Y-572571D01*
X210800Y-573105D01*
X210400Y-573905D01*
X210200Y-574971D01*
X210400Y-576038D01*
X210800Y-576838D01*
X211400Y-577371D01*
X212100Y-577638D01*
X212800Y-577505D01*
X213400Y-577105D01*
X213800Y-576572D01*
G01X217900Y-580038D02*
X218500Y-580305D01*
X219300Y-580038D01*
X219800Y-579505D01*
X220200Y-578838D01*
X220800Y-576705D01*
X222100Y-572305D01*
G01X218900D02*
X220800Y-576705D01*
G01X226500Y-574038D02*
X229700D01*
X229400Y-573105D01*
X228900Y-572571D01*
X228200Y-572305D01*
X227500Y-572438D01*
X226900Y-572838D01*
X226500Y-573771D01*
X226300Y-574572D01*
Y-575371D01*
X226500Y-576171D01*
X227000Y-576971D01*
X227600Y-577505D01*
X228300Y-577638D01*
X229000Y-577371D01*
X229700Y-576572D01*
G01X234600Y-577638D02*
Y-572305D01*
G01Y-573371D02*
X235100Y-572838D01*
X235600Y-572438D01*
X236300Y-572305D01*
X236800Y-572438D01*
X237400Y-572838D01*
G01X226000Y-626038D02*
X226500Y-626838D01*
X227100Y-627371D01*
X227800Y-627638D01*
X228600Y-627371D01*
X229200Y-626838D01*
X229800Y-626038D01*
X230000Y-624971D01*
Y-619638D01*
G01X237800Y-627638D02*
Y-622305D01*
G01Y-623238D02*
X237400Y-622705D01*
X236800Y-622438D01*
X236100Y-622305D01*
X235400Y-622571D01*
X234800Y-623105D01*
X234400Y-623905D01*
X234200Y-624971D01*
X234400Y-626038D01*
X234800Y-626838D01*
X235400Y-627371D01*
X236100Y-627638D01*
X236800Y-627505D01*
X237400Y-627105D01*
X237800Y-626572D01*
G01X245600Y-622971D02*
X244900Y-622438D01*
X244300Y-622305D01*
X243500Y-622571D01*
X242900Y-623105D01*
X242500Y-624038D01*
X242400Y-624971D01*
X242500Y-625905D01*
X242900Y-626705D01*
X243500Y-627371D01*
X244300Y-627638D01*
X245000Y-627371D01*
X245600Y-626838D01*
G01X250300Y-627638D02*
Y-619638D01*
G01X253500Y-622305D02*
X250300Y-625371D01*
G01X251600Y-624171D02*
X253700Y-627638D01*
G01X328600Y-620971D02*
X329200Y-620171D01*
X329900Y-619771D01*
X330700Y-619638D01*
X331700Y-619905D01*
X332400Y-620571D01*
X332600Y-621371D01*
X332500Y-622172D01*
X332100Y-622838D01*
X330100Y-624171D01*
X329200Y-625105D01*
X328600Y-626438D01*
X328400Y-627638D01*
X332600D01*
G01X338500Y-619638D02*
X337700Y-619905D01*
X337100Y-620571D01*
X336700Y-621371D01*
X336400Y-622438D01*
X336300Y-623638D01*
X336400Y-624838D01*
X336700Y-625905D01*
X337100Y-626705D01*
X337700Y-627371D01*
X338500Y-627638D01*
X339300Y-627371D01*
X339900Y-626705D01*
X340300Y-625905D01*
X340600Y-624838D01*
X340700Y-623638D01*
X340600Y-622438D01*
X340300Y-621371D01*
X339900Y-620571D01*
X339300Y-619905D01*
X338500Y-619638D01*
G01X344600Y-620971D02*
X345200Y-620171D01*
X345900Y-619771D01*
X346700Y-619638D01*
X347700Y-619905D01*
X348400Y-620571D01*
X348600Y-621371D01*
X348500Y-622172D01*
X348100Y-622838D01*
X346100Y-624171D01*
X345200Y-625105D01*
X344600Y-626438D01*
X344400Y-627638D01*
X348600D01*
G01X352300Y-626038D02*
X352900Y-626971D01*
X353700Y-627505D01*
X354600Y-627638D01*
X355400Y-627505D01*
X356200Y-626838D01*
X356700Y-626038D01*
X356800Y-625238D01*
X356600Y-624305D01*
X355900Y-623638D01*
X355200Y-623371D01*
X354300D01*
G01X355200D02*
X355800Y-622971D01*
X356300Y-622305D01*
X356500Y-621505D01*
X356300Y-620705D01*
X355800Y-620038D01*
X354900Y-619638D01*
X354000Y-619771D01*
X353100Y-620305D01*
G01X360700Y-627905D02*
X364300Y-619638D01*
G01X370500D02*
X369700Y-619905D01*
X369100Y-620571D01*
X368700Y-621371D01*
X368400Y-622438D01*
X368300Y-623638D01*
X368400Y-624838D01*
X368700Y-625905D01*
X369100Y-626705D01*
X369700Y-627371D01*
X370500Y-627638D01*
X371300Y-627371D01*
X371900Y-626705D01*
X372300Y-625905D01*
X372600Y-624838D01*
X372700Y-623638D01*
X372600Y-622438D01*
X372300Y-621371D01*
X371900Y-620571D01*
X371300Y-619905D01*
X370500Y-619638D01*
G01X379700Y-627638D02*
Y-619638D01*
X376000Y-625371D01*
X381000D01*
G01X384700Y-627905D02*
X388300Y-619638D01*
G01X394500Y-627638D02*
Y-619638D01*
X393300Y-621238D01*
G01Y-627638D02*
X395700D01*
G01X402300D02*
X402500Y-625905D01*
X402800Y-624438D01*
X403200Y-623105D01*
X403700Y-621638D01*
X404500Y-619638D01*
X400500D01*
G01X328300Y-602638D02*
Y-594638D01*
X330300D01*
X331100Y-595038D01*
X331700Y-595571D01*
X332200Y-596371D01*
X332600Y-597305D01*
X332700Y-598638D01*
X332600Y-599971D01*
X332200Y-600905D01*
X331700Y-601705D01*
X331100Y-602238D01*
X330300Y-602638D01*
X328300D01*
G01X336000D02*
X338500Y-594638D01*
X341000Y-602638D01*
G01X340100Y-599838D02*
X336900D01*
G01X344600Y-602638D02*
Y-594638D01*
X348400D01*
G01X347000Y-598505D02*
X344600D01*
G01X354500Y-594638D02*
X353700Y-594905D01*
X353100Y-595571D01*
X352700Y-596371D01*
X352400Y-597438D01*
X352300Y-598638D01*
X352400Y-599838D01*
X352700Y-600905D01*
X353100Y-601705D01*
X353700Y-602371D01*
X354500Y-602638D01*
X355300Y-602371D01*
X355900Y-601705D01*
X356300Y-600905D01*
X356600Y-599838D01*
X356700Y-598638D01*
X356600Y-597438D01*
X356300Y-596371D01*
X355900Y-595571D01*
X355300Y-594905D01*
X354500Y-594638D01*
G01X362500D02*
Y-602638D01*
G01X360200Y-594638D02*
X364800D01*
G01X367900Y-602638D02*
Y-594638D01*
X370500Y-601305D01*
X373100Y-594638D01*
Y-602638D01*
G01X379300Y-598371D02*
X379700Y-597971D01*
X380000Y-597305D01*
X380200Y-596371D01*
X380000Y-595571D01*
X379600Y-595038D01*
X378900Y-594638D01*
X376200D01*
Y-602638D01*
X379500D01*
X380200Y-602105D01*
X380600Y-601305D01*
X380800Y-600371D01*
X380600Y-599438D01*
X380000Y-598638D01*
X379300Y-598371D01*
X376200D01*
G01X384300Y-601038D02*
X384900Y-601971D01*
X385700Y-602505D01*
X386600Y-602638D01*
X387400Y-602505D01*
X388200Y-601838D01*
X388700Y-601038D01*
X388800Y-600238D01*
X388600Y-599305D01*
X387900Y-598638D01*
X387200Y-598371D01*
X386300D01*
G01X387200D02*
X387800Y-597971D01*
X388300Y-597305D01*
X388500Y-596505D01*
X388300Y-595705D01*
X387800Y-595038D01*
X386900Y-594638D01*
X386000Y-594771D01*
X385100Y-595305D01*
G01X393300Y-594638D02*
X395700D01*
G01X394500D02*
Y-602638D01*
G01X393300D02*
X395700D01*
G01X404700Y-595305D02*
X404100Y-594905D01*
X403400Y-594638D01*
X402600D01*
X401700Y-595038D01*
X401000Y-595705D01*
X400500Y-596505D01*
X400100Y-597838D01*
X400000Y-599038D01*
X400200Y-600238D01*
X400500Y-601038D01*
X401100Y-601838D01*
X401800Y-602371D01*
X402500Y-602638D01*
X403200D01*
X403900Y-602371D01*
X404500Y-601971D01*
X405000Y-601438D01*
G01X410500Y-594638D02*
X409700Y-594905D01*
X409100Y-595571D01*
X408700Y-596371D01*
X408400Y-597438D01*
X408300Y-598638D01*
X408400Y-599838D01*
X408700Y-600905D01*
X409100Y-601705D01*
X409700Y-602371D01*
X410500Y-602638D01*
X411300Y-602371D01*
X411900Y-601705D01*
X412300Y-600905D01*
X412600Y-599838D01*
X412700Y-598638D01*
X412600Y-597438D01*
X412300Y-596371D01*
X411900Y-595571D01*
X411300Y-594905D01*
X410500Y-594638D01*
G01X346100Y-577638D02*
Y-569638D01*
X349900D01*
G01X348500Y-573505D02*
X346100D01*
G01X356000Y-569638D02*
X355200Y-569905D01*
X354600Y-570571D01*
X354200Y-571371D01*
X353900Y-572438D01*
X353800Y-573638D01*
X353900Y-574838D01*
X354200Y-575905D01*
X354600Y-576705D01*
X355200Y-577371D01*
X356000Y-577638D01*
X356800Y-577371D01*
X357400Y-576705D01*
X357800Y-575905D01*
X358100Y-574838D01*
X358200Y-573638D01*
X358100Y-572438D01*
X357800Y-571371D01*
X357400Y-570571D01*
X356800Y-569905D01*
X356000Y-569638D01*
G01X364000D02*
Y-577638D01*
G01X361700Y-569638D02*
X366300D01*
G01X372600Y-573638D02*
X374600D01*
Y-576038D01*
X374000Y-576838D01*
X373300Y-577371D01*
X372300Y-577638D01*
X371300Y-577371D01*
X370600Y-576838D01*
X370000Y-576038D01*
X369600Y-575105D01*
X369400Y-574038D01*
Y-573105D01*
X369600Y-572305D01*
X370000Y-571371D01*
X370600Y-570571D01*
X371200Y-570038D01*
X372000Y-569638D01*
X372700D01*
X373500Y-569905D01*
X374100Y-570438D01*
G01X377000Y-580305D02*
X383000D01*
G01X385400Y-577638D02*
Y-569638D01*
X388000Y-576305D01*
X390600Y-569638D01*
Y-577638D01*
G01X396800Y-573371D02*
X397200Y-572971D01*
X397500Y-572305D01*
X397700Y-571371D01*
X397500Y-570571D01*
X397100Y-570038D01*
X396400Y-569638D01*
X393700D01*
Y-577638D01*
X397000D01*
X397700Y-577105D01*
X398100Y-576305D01*
X398300Y-575371D01*
X398100Y-574438D01*
X397500Y-573638D01*
X396800Y-573371D01*
X393700D01*
G01X417000Y-630638D02*
Y-622638D01*
X415800Y-624238D01*
G01Y-630638D02*
X418200D01*
G01X423100Y-627305D02*
X423800Y-626371D01*
X424400Y-625838D01*
X425200Y-625571D01*
X425900Y-625838D01*
X426400Y-626371D01*
X426800Y-627171D01*
X426900Y-628105D01*
X426800Y-628905D01*
X426400Y-629705D01*
X425800Y-630371D01*
X425100Y-630638D01*
X424300Y-630371D01*
X423600Y-629572D01*
X423200Y-628371D01*
X423100Y-627038D01*
X423300Y-625305D01*
X423600Y-624371D01*
X424100Y-623438D01*
X424800Y-622771D01*
X425500Y-622638D01*
X426200Y-622905D01*
X426700Y-623571D01*
G01X433000Y-630905D02*
X432800Y-630771D01*
Y-630505D01*
X433000Y-630371D01*
X433200Y-630505D01*
Y-630771D01*
X433000Y-630905D01*
G01X439100Y-627305D02*
X439800Y-626371D01*
X440400Y-625838D01*
X441200Y-625571D01*
X441900Y-625838D01*
X442400Y-626371D01*
X442800Y-627171D01*
X442900Y-628105D01*
X442800Y-628905D01*
X442400Y-629705D01*
X441800Y-630371D01*
X441100Y-630638D01*
X440300Y-630371D01*
X439600Y-629572D01*
X439200Y-628371D01*
X439100Y-627038D01*
X439300Y-625305D01*
X439600Y-624371D01*
X440100Y-623438D01*
X440800Y-622771D01*
X441500Y-622638D01*
X442200Y-622905D01*
X442700Y-623571D01*
G01X462000Y-630638D02*
Y-622638D01*
X460800Y-624238D01*
G01Y-630638D02*
X463200D01*
G01X469800D02*
X470000Y-628905D01*
X470300Y-627438D01*
X470700Y-626105D01*
X471200Y-624638D01*
X472000Y-622638D01*
X468000D01*
G01X478000Y-630905D02*
X477800Y-630771D01*
Y-630505D01*
X478000Y-630371D01*
X478200Y-630505D01*
Y-630771D01*
X478000Y-630905D01*
G01X484100Y-623971D02*
X484700Y-623171D01*
X485400Y-622771D01*
X486200Y-622638D01*
X487200Y-622905D01*
X487900Y-623571D01*
X488100Y-624371D01*
X488000Y-625172D01*
X487600Y-625838D01*
X485600Y-627171D01*
X484700Y-628105D01*
X484100Y-629438D01*
X483900Y-630638D01*
X488100D01*
G01X486200Y-598305D02*
X485600Y-597905D01*
X484900Y-597638D01*
X484100D01*
X483200Y-598038D01*
X482500Y-598705D01*
X482000Y-599505D01*
X481600Y-600838D01*
X481500Y-602038D01*
X481700Y-603238D01*
X482000Y-604038D01*
X482600Y-604838D01*
X483300Y-605371D01*
X484000Y-605638D01*
X484700D01*
X485400Y-605371D01*
X486000Y-604971D01*
X486500Y-604438D01*
G54D10*
X20709Y139746D03*
X23563Y1590338D03*
X409259Y412106D03*
X864625Y1368522D03*
X925009Y1014595D03*
X1088663Y299646D03*
X1489957Y1403002D03*
X1568792Y178239D03*
X1704930Y1649379D03*
G54D20*
X30000Y1505100D03*
Y1510900D03*
X499586Y161518D03*
Y167318D03*
X543749Y123617D03*
Y129417D03*
X537242Y164428D03*
Y158628D03*
X553380Y138093D03*
Y143893D03*
X1823514Y1529093D03*
Y1534893D03*
G54D11*
X11782Y167036D03*
X18691Y167208D03*
X22409Y230021D03*
X19684Y237154D03*
X17292Y290137D03*
X16681Y1451841D03*
X35689Y301357D03*
X36722Y327797D03*
X35740Y363337D03*
X39320Y392269D03*
X29962Y401000D03*
X33350Y434992D03*
X27520D03*
X38620Y447202D03*
X38480Y441482D03*
X39967Y526709D03*
X30562Y533055D03*
X38181Y1451841D03*
X45423Y197224D03*
Y212224D03*
Y202224D03*
Y207224D03*
X42449Y282916D03*
Y277798D03*
X47892Y290137D03*
X41492Y298207D03*
X47892Y295452D03*
X40500Y288500D03*
X55254Y292892D03*
X42449Y312916D03*
Y307798D03*
X46988Y324563D03*
X55190Y360862D03*
X42809D03*
X40940Y387302D03*
X53825Y421746D03*
X55099Y1298676D03*
Y1292676D03*
X44019Y1518990D03*
X47735Y1584885D03*
X47973Y1589981D03*
X43633Y1606896D03*
X43933Y1613818D03*
X47633Y1600896D03*
X53633Y1629896D03*
X41208Y1619896D03*
X41427Y1668587D03*
X52052Y1684027D03*
X66650Y265316D03*
X62930Y282866D03*
X66289Y301357D03*
X62930Y312866D03*
X57920Y443702D03*
Y448702D03*
X65391Y524549D03*
X62142Y539495D03*
X64883Y748766D03*
X61620Y768510D03*
X56440Y766180D03*
X62181Y1451841D03*
X56218Y1535114D03*
X66229Y1549536D03*
X57850Y1542141D03*
X57811Y1598061D03*
X58633Y1587481D03*
X63633D03*
X58633Y1629896D03*
X64133Y1627896D03*
X64633Y1632896D03*
X70127Y1687362D03*
X82026Y143491D03*
X71659Y149191D03*
X71779Y161194D03*
X71500Y390812D03*
X71772Y421746D03*
X76378Y1406622D03*
X83441Y1430500D03*
X72375Y1604365D03*
X74133Y1610896D03*
X79679Y1605289D03*
X70567Y1625603D03*
X72255Y1616730D03*
X74134Y1621396D03*
X75380Y1627622D03*
X79164Y1636992D03*
X78127Y1687362D03*
X82500Y1698511D03*
Y1706511D03*
X82000Y1716331D03*
Y1724331D03*
X92197Y143853D03*
X87137Y143663D03*
X93775Y197241D03*
Y212241D03*
Y207241D03*
Y202241D03*
X87654Y376026D03*
X87520Y386502D03*
X92159Y750500D03*
X87260Y766947D03*
X90150Y1314560D03*
X93000Y1444500D03*
X88293Y1446638D03*
X86181Y1451841D03*
X93296Y1549142D03*
X93318Y1542141D03*
X96101Y1696469D03*
X96555Y1705508D03*
X95400Y1719741D03*
X95460Y1725241D03*
X104829Y151191D03*
X107931Y158767D03*
X100818Y168906D03*
X105296Y1375946D03*
X101995Y1388247D03*
X111600Y1403100D03*
X101637Y1432938D03*
X102076Y1427833D03*
X102398Y1440000D03*
X113500Y1455600D03*
X112100Y1467500D03*
X100439Y1667361D03*
X100915Y1679564D03*
X106448Y1696436D03*
X107500Y1707450D03*
X120016Y300654D03*
Y320631D03*
X122159Y750266D03*
X116878Y766757D03*
X122050Y1403750D03*
X129200Y1401000D03*
X126000Y1414000D03*
X116700Y1415700D03*
Y1410500D03*
X116900Y1449000D03*
X119100Y1460300D03*
X124312Y1633488D03*
X115353Y1695941D03*
X127710Y1700166D03*
X120052Y1712450D03*
X127290Y1705666D03*
X125183Y1716741D03*
X127168Y1721695D03*
X129020Y1726741D03*
X134812Y530955D03*
X140471Y670445D03*
X134902Y668506D03*
X140600Y683029D03*
X134902Y686074D03*
X140265Y1297380D03*
X137896Y1375946D03*
X138000Y1400600D03*
X134800Y1408100D03*
X133349Y1434651D03*
X141500Y1433500D03*
X139500Y1446000D03*
X133100Y1444100D03*
X138013Y1440487D03*
X133120Y1454751D03*
X141028Y1454705D03*
X137386Y1626412D03*
X131353Y1696062D03*
X139353D03*
X143000Y1701011D03*
Y1709166D03*
X149231Y224204D03*
X148228Y216118D03*
X158380Y419760D03*
X147450Y423860D03*
X154770Y441830D03*
X147810Y475710D03*
X146982Y526997D03*
X159513Y674855D03*
X152705Y683218D03*
X151659Y749766D03*
X146663Y766347D03*
X156477Y1447733D03*
X154305Y1453101D03*
X159000Y1525480D03*
X149171Y1616759D03*
X159427Y1687843D03*
Y1696652D03*
X152605Y1715941D03*
X149338Y1705603D03*
X146000Y1718241D03*
X155740Y1729726D03*
X146483Y1725636D03*
X162830Y396930D03*
X172010Y474900D03*
X163372Y670863D03*
X172725Y667898D03*
X162482Y679319D03*
X161735Y684456D03*
X172725Y679230D03*
X172965Y1297380D03*
X170266Y1344588D03*
X170596Y1375946D03*
X163148Y1474504D03*
X172180Y1490210D03*
X172070Y1495550D03*
X162740Y1713172D03*
X171925Y1708428D03*
X171945Y1730693D03*
X162740Y1723886D03*
X187250Y129674D03*
X189290Y396730D03*
X177675Y419260D03*
X185160Y419220D03*
X181550Y441290D03*
X181159Y750766D03*
X176326Y766615D03*
X186682Y1344588D03*
X176510Y1509270D03*
X174630Y1522540D03*
X176265Y1515524D03*
X180127Y1551756D03*
X182115Y1572260D03*
X181099Y1656804D03*
X175927Y1651506D03*
X184139Y1651088D03*
X179443Y1661581D03*
X182533Y1676854D03*
X184340Y1718000D03*
X178385Y1715441D03*
X178376Y1720559D03*
X195979Y109462D03*
X203061Y131158D03*
X201024Y571472D03*
X200754Y595174D03*
X200405Y632385D03*
X203496Y1375946D03*
X200488Y1557334D03*
X199747Y1675603D03*
X197780Y1696973D03*
X200478Y1701758D03*
X200448Y1690771D03*
X202076Y1717845D03*
X189760Y1713061D03*
X203510Y1712441D03*
X189760Y1723041D03*
X203655Y1723000D03*
X214107Y113022D03*
X205489Y142790D03*
X217687Y522453D03*
X218493Y684406D03*
X210993Y691906D03*
X218493Y699406D03*
X212400Y750200D03*
X215753Y767266D03*
X205865Y1297380D03*
X212365Y1705403D03*
X224055Y127146D03*
X233284Y137195D03*
X233653Y162074D03*
X223687Y522453D03*
X229687D03*
X233024Y567572D03*
X233493Y676906D03*
Y684406D03*
X225993Y691906D03*
Y706906D03*
X230771Y1259005D03*
X229994Y1344971D03*
X223671Y1546805D03*
X230052Y1559984D03*
X238059Y26235D03*
X235697Y21585D03*
X241306Y20325D03*
X246356Y26855D03*
X248816Y48965D03*
X239816Y54365D03*
X248487Y68690D03*
X242920Y67915D03*
X238846Y72977D03*
X235186Y98067D03*
X242215Y151788D03*
X236104Y151996D03*
X245486Y159705D03*
X240413Y360867D03*
X248493Y684406D03*
X240200Y766300D03*
X247058Y1344988D03*
X236296Y1375946D03*
X251106Y12615D03*
X257516Y51565D03*
X251793Y100846D03*
X252800Y114800D03*
X252195Y144320D03*
X249735Y152694D03*
X262886Y147391D03*
X253024Y567572D03*
Y587572D03*
Y607572D03*
X263493Y684406D03*
X263287Y740260D03*
X257071Y772770D03*
X252079Y1290037D03*
X251249Y1560542D03*
X275116Y28565D03*
X275896Y48875D03*
X266420Y39120D03*
X265365Y49171D03*
X267931Y59250D03*
X267995Y68344D03*
X273616Y96665D03*
X264293Y120972D03*
X269487Y121095D03*
X275793Y120248D03*
X266000Y125800D03*
X276821Y140465D03*
X264574Y159206D03*
X269925Y217700D03*
X274993Y522052D03*
X265100Y595078D03*
X267601Y608378D03*
X271571Y644796D03*
X265782Y653947D03*
X270857Y668515D03*
X271161Y780588D03*
X274282Y786741D03*
X272395Y1329656D03*
X264085Y1339175D03*
X267918Y1508216D03*
X264671Y1512470D03*
X264770Y1518000D03*
X269378Y1555103D03*
X286996Y20365D03*
X290795Y28365D03*
X287988Y54893D03*
X293157Y50525D03*
X286996Y139865D03*
X285865Y596970D03*
X290865Y609470D03*
X293817Y687986D03*
X287995Y1553934D03*
X295516Y26365D03*
X300244Y28365D03*
X299496Y22865D03*
X303252Y38199D03*
X295308Y43227D03*
X296337Y55855D03*
X298542Y51088D03*
X303711Y50860D03*
X301107Y75676D03*
X305820Y73693D03*
X301780Y82900D03*
X299002Y88700D03*
X307816Y95727D03*
X299628Y149203D03*
X299624Y158706D03*
X306528Y256528D03*
X294299Y577188D03*
X302130Y584160D03*
X305865Y596970D03*
X304449Y609570D03*
X304301Y679037D03*
X296117Y774610D03*
X305175Y1243788D03*
X305291Y1329628D03*
X304505Y1509298D03*
X303369Y1520193D03*
X305148Y1515299D03*
X303406Y1557752D03*
X323036Y73125D03*
X310455Y75895D03*
X320190Y77648D03*
X322871Y84321D03*
X316982Y89003D03*
X322174Y97472D03*
Y112472D03*
Y127472D03*
X323646Y147120D03*
Y152120D03*
X314780Y545716D03*
X322955Y556148D03*
X311349Y609632D03*
X326475Y182855D03*
X331780Y182900D03*
X324406Y367744D03*
X334744Y566086D03*
X326393Y708136D03*
X328887Y794660D03*
X338195Y1329571D03*
X326277Y1560681D03*
X343036Y122525D03*
X343446Y131170D03*
X339914Y165170D03*
X344984Y199299D03*
X352000Y230643D03*
Y235643D03*
X353288Y578508D03*
X342275Y1546793D03*
X349426Y1560262D03*
X366874Y135157D03*
X366771Y127665D03*
X355910Y223847D03*
X365739Y221871D03*
X365559Y238896D03*
X357600Y543080D03*
X363100Y585960D03*
X360467Y581734D03*
X359854Y707868D03*
X364671Y824846D03*
X359371Y824688D03*
X360071Y831388D03*
X359071Y838888D03*
X361922Y1206891D03*
X357271Y1208988D03*
X356430Y1546724D03*
X375920Y146577D03*
X377118Y222229D03*
X370327Y228951D03*
X370352Y235455D03*
X382184Y466351D03*
X378976Y479226D03*
X375410Y552254D03*
X375271Y542191D03*
X369271Y600138D03*
X373477Y593338D03*
X370575Y1243845D03*
X371089Y1329865D03*
X373971Y1559565D03*
X375050Y1639400D03*
X371823Y1644516D03*
X370533Y1658605D03*
X374962Y1648511D03*
X372953Y1653197D03*
X373330Y1668539D03*
X391600Y121178D03*
X387712Y147441D03*
X395590Y147010D03*
X391635Y161091D03*
X397184Y507101D03*
X387440Y525154D03*
X392554Y557081D03*
X394168Y568482D03*
X386071Y587138D03*
X393315Y707936D03*
X387446Y1207488D03*
X395267Y1358621D03*
X395980Y1508216D03*
X392792Y1512252D03*
X392830Y1518020D03*
X392936Y1557334D03*
X389276Y1568413D03*
X393322Y1573347D03*
X388784Y1581801D03*
X393005Y1592304D03*
X387805Y1604802D03*
X394824Y1629713D03*
X394000Y1621500D03*
X389824Y1629713D03*
X389000Y1621500D03*
X384824Y1629713D03*
X406243Y100076D03*
X403734Y110326D03*
X410678Y159140D03*
X411299Y212096D03*
X411940Y240501D03*
X410984Y496649D03*
X410111Y572608D03*
X403461Y1263319D03*
X403577Y1349102D03*
X408895Y1553644D03*
X407198Y1564990D03*
X401249Y1564422D03*
X405758Y1557900D03*
X403163Y1579357D03*
X404669Y1594317D03*
X401667Y1602636D03*
X400380Y1621500D03*
X408994Y1642292D03*
X404640Y1637425D03*
X412000Y1647177D03*
X403844Y1665769D03*
X406500Y1672500D03*
X405000Y1683500D03*
X416549Y66365D03*
Y71665D03*
X427300Y71300D03*
X419900Y96620D03*
X414100D03*
X422936Y223501D03*
X420115Y230323D03*
Y240501D03*
Y235442D03*
X419984Y508000D03*
X425152Y690136D03*
X415158Y774175D03*
X424107Y1553934D03*
X424488Y1565400D03*
X413540Y1556646D03*
X419254Y1566828D03*
X427081Y1581620D03*
X425166Y1602365D03*
X423722Y1625728D03*
X421500Y1657500D03*
X423500Y1652500D03*
X420000Y1668075D03*
X417000Y1683500D03*
X433673Y73960D03*
X428149Y65016D03*
X429685Y88657D03*
X431359Y82589D03*
X429997Y166400D03*
X441997D03*
X436103Y158594D03*
X438200Y212096D03*
X431299Y212095D03*
X437440Y237270D03*
X442710Y237990D03*
X435710Y250340D03*
X440710D03*
X437084Y501865D03*
X442084Y511870D03*
X440030Y1508070D03*
X439480Y1520193D03*
X441259Y1515299D03*
X439935Y1532600D03*
X431923Y1565790D03*
X440769Y1556778D03*
X433440Y1581700D03*
X439980Y1599330D03*
X429947Y1594398D03*
X433012Y1621612D03*
X437910Y1638091D03*
X432000Y1650000D03*
X440075Y1650073D03*
X445267Y82124D03*
X448038Y158659D03*
X445997Y170701D03*
X448499Y212036D03*
X443299Y212095D03*
X456231Y227764D03*
Y232883D03*
X446710Y249340D03*
X453269Y478388D03*
X443683Y502256D03*
X447084Y511870D03*
X457084D03*
X457356Y665536D03*
X446686Y744660D03*
X451740Y1302070D03*
Y1382070D03*
X445873Y1596163D03*
X444128Y1604200D03*
X446182Y1625555D03*
X462000Y147090D03*
X472000D03*
X465997Y166400D03*
X457997D03*
X471371Y227764D03*
Y222764D03*
X460567Y225205D03*
Y235442D03*
X460624Y230323D03*
X470243Y285693D03*
X460441Y499842D03*
X468638Y514096D03*
X465766Y524991D03*
X462490Y734528D03*
X471740Y1302070D03*
Y1322070D03*
Y1362070D03*
Y1382070D03*
X460712Y1559986D03*
X459500Y1659000D03*
X468350Y1645351D03*
X468075Y1662500D03*
X470309Y1689000D03*
X468575Y1704000D03*
Y1731000D03*
X479400Y90574D03*
X482000Y147090D03*
X486682Y197516D03*
X487620Y270400D03*
X479870D03*
X483823Y285893D03*
X484063Y305669D03*
X481239Y312352D03*
X479058Y720660D03*
X483722Y1560823D03*
X483500Y1658500D03*
X479500Y1666500D03*
X473500Y1662500D03*
X476000Y1680000D03*
X478500Y1701000D03*
X474000Y1704000D03*
X478500Y1714500D03*
X500674Y116261D03*
X495232Y189516D03*
X496831Y205030D03*
X494144Y221370D03*
X500209Y227881D03*
Y233000D03*
X491859D03*
X500119Y243173D03*
X489232Y290418D03*
X488405Y578572D03*
X501171Y630087D03*
X490976Y639036D03*
X494862Y708028D03*
X491740Y1302070D03*
Y1322070D03*
Y1342070D03*
Y1362070D03*
Y1382070D03*
X487801Y1546725D03*
X502750Y111276D03*
X505315Y196944D03*
X504351Y202776D03*
X512076Y206404D03*
X508001Y220166D03*
X507569Y1559567D03*
X524713Y33346D03*
X529713D03*
X524400Y167680D03*
X519601Y196117D03*
X524798Y299035D03*
Y309035D03*
X529095Y452049D03*
X524752Y604936D03*
X530493Y628906D03*
X527458Y681460D03*
X518075Y845663D03*
X532091Y1508216D03*
X528890Y1517960D03*
X529025Y1512306D03*
X527651Y1559707D03*
X544721Y42892D03*
X539721Y42862D03*
X534277Y224930D03*
X538613Y227882D03*
Y238119D03*
X534277Y230441D03*
X538613Y233000D03*
X538968Y258261D03*
X534455Y428561D03*
X543997Y1654500D03*
X553651Y48842D03*
X550972Y42902D03*
X561721Y41024D03*
X556351Y41538D03*
X548610Y48082D03*
X558500Y138880D03*
X549248Y237652D03*
Y230441D03*
X558968Y258403D03*
X562030Y372872D03*
X562208Y383668D03*
Y404717D03*
Y397599D03*
X555727Y479968D03*
X550493Y563906D03*
Y583906D03*
Y603906D03*
Y628906D03*
X552169Y1553934D03*
X565185Y47982D03*
X575331Y47672D03*
X573191Y42912D03*
X570209Y47982D03*
X566771Y41133D03*
X571933Y66587D03*
X563951Y153640D03*
Y148640D03*
Y160644D03*
X572003Y164356D03*
X569004Y225496D03*
X570823Y294893D03*
X564400Y317260D03*
X575913Y413287D03*
X570863Y410728D03*
X572121Y437038D03*
X564407Y431638D03*
X563763Y486350D03*
X570493Y563906D03*
Y583906D03*
Y603906D03*
Y628906D03*
X575600Y1257350D03*
X563596Y1268118D03*
X568605Y1509322D03*
X567542Y1520193D03*
X569321Y1515299D03*
X566978Y1555522D03*
X591938Y46308D03*
X591070Y60201D03*
X586953Y63441D03*
X590501Y86909D03*
X580098Y96439D03*
X586394Y95948D03*
X591811Y97421D03*
X589203Y164356D03*
Y169415D03*
X588215Y214079D03*
X588968Y240112D03*
X590900Y258260D03*
X585303Y303170D03*
Y318170D03*
X585585Y372052D03*
X577482Y383668D03*
X587710Y399287D03*
Y404287D03*
X588798Y435949D03*
X588723Y427949D03*
X589507Y462559D03*
X583116Y476745D03*
X581335Y472100D03*
X580614Y776454D03*
X584271Y1263988D03*
X578484Y1268948D03*
X585386Y1559357D03*
X602837Y32910D03*
X603064Y48023D03*
X599284Y42481D03*
X597956Y48047D03*
X606585Y43529D03*
X599295Y100747D03*
X606183Y95873D03*
X597275Y94922D03*
X596068Y106798D03*
X597769Y153640D03*
Y148640D03*
X604293Y193185D03*
X597293Y193186D03*
X602294Y203786D03*
X598968Y238878D03*
X598208Y383668D03*
X593758Y415850D03*
X597500Y483500D03*
X602584Y1246888D03*
X596944Y1270115D03*
X605771Y1263098D03*
X598112Y1264365D03*
X619563Y49193D03*
X615587Y45611D03*
X618182Y100786D03*
X610009Y100748D03*
X614282Y95873D03*
X618801Y165356D03*
Y175534D03*
Y170415D03*
X608794Y203786D03*
X621585Y331358D03*
X613565Y350819D03*
X613482Y383668D03*
X617985Y401728D03*
X618680Y511302D03*
X611896Y538178D03*
X607091Y528168D03*
X620234Y751615D03*
X619695Y758764D03*
X607671Y1246088D03*
X615591Y1282038D03*
X608148Y1373890D03*
X612041Y1379093D03*
X609241Y1388552D03*
X615921Y1546725D03*
X609093Y1560264D03*
X624634Y48104D03*
X627881Y57120D03*
X622207Y60573D03*
X636070Y76336D03*
X626642Y71365D03*
X632096Y80536D03*
X622156Y95948D03*
X626208Y100861D03*
X630900Y118920D03*
X622705Y285305D03*
X636500Y360362D03*
X634105Y404652D03*
X635058Y399700D03*
X627925Y421966D03*
X622800Y461348D03*
X627880Y455310D03*
X627364Y478823D03*
X635567Y671774D03*
X624537Y765541D03*
X632479Y781595D03*
X629511Y789048D03*
X626112Y1301920D03*
X632983Y1297148D03*
X633406Y1358576D03*
X634776Y1353739D03*
X624795Y1373257D03*
X624976Y1378313D03*
X630195Y1384263D03*
X625195Y1383457D03*
X622352Y1393285D03*
X630523Y1392554D03*
X635849Y1393376D03*
X629593Y1560543D03*
X623205Y1639099D03*
X623175Y1644227D03*
X631961Y1651949D03*
X633422Y1673488D03*
X635491Y1696845D03*
X635472Y1711808D03*
X642157Y44695D03*
X639876Y49193D03*
X651042Y41545D03*
X647987Y47606D03*
X646042Y41545D03*
X640653Y58274D03*
X645814Y60051D03*
X650846Y74074D03*
X647938Y83795D03*
X642607Y94116D03*
X642394Y131172D03*
X645752Y134988D03*
X649871Y181942D03*
X642617Y389299D03*
X637314Y393680D03*
X651279Y404458D03*
X648500Y453862D03*
X644849Y495582D03*
X640076Y497964D03*
X649592Y540078D03*
X646151Y535227D03*
X650228Y674761D03*
X640990Y750766D03*
X648838Y1561659D03*
X646630Y1626990D03*
X646522Y1621820D03*
X645320Y1633260D03*
X637524Y1642010D03*
X642716Y1653939D03*
X637218Y1654131D03*
X644905Y1646491D03*
X639800Y1646650D03*
X647460Y1662952D03*
X640846Y1665189D03*
X650158Y1687189D03*
X643041Y1682883D03*
X650505Y1681978D03*
X637206Y1676799D03*
X643300Y1677689D03*
X651143Y1706162D03*
X644975Y1725236D03*
X654117Y29099D03*
X654582Y45448D03*
X653892Y54314D03*
X661601Y75562D03*
X661588Y69662D03*
X658228Y88447D03*
X666200Y84862D03*
X654037Y96041D03*
X663915Y234476D03*
X658905Y341885D03*
X653523Y399987D03*
X652954Y394284D03*
X662000Y433862D03*
X666000Y429844D03*
X652763Y427866D03*
X657622Y437819D03*
X651853Y439518D03*
X666000Y473844D03*
X651937Y469576D03*
X660215Y483109D03*
X665689Y550294D03*
X660175Y679517D03*
X665417Y768090D03*
X665000Y1329100D03*
Y1349100D03*
X653376Y1365793D03*
X657916Y1362163D03*
X654992Y1380836D03*
X660153Y1508216D03*
X661710Y1514148D03*
X666092Y1553650D03*
X657430Y1555228D03*
X653542Y1649059D03*
X660389Y1654481D03*
X657801Y1676898D03*
X652379Y1676984D03*
X660930Y1730277D03*
X662120Y1720404D03*
X680864Y38190D03*
X674647D03*
X674036Y74522D03*
X667941Y80142D03*
X680800Y380280D03*
X676000Y378100D03*
X667090Y385150D03*
X679940Y400933D03*
X680171Y417859D03*
X680175Y445862D03*
Y458862D03*
X679648Y465862D03*
X678000Y477862D03*
Y482862D03*
X681213Y495658D03*
X680488Y504784D03*
X670490Y752266D03*
X680776Y1297506D03*
X678552Y1361408D03*
X669857Y1528502D03*
X667971Y1654404D03*
X669178Y1646627D03*
X673480Y1662668D03*
X680080Y1678937D03*
X667882Y1676962D03*
X671631Y1690786D03*
X667852Y1695577D03*
X667817Y1710439D03*
X667701Y1705043D03*
X684611Y41857D03*
X682291Y46822D03*
X692390Y46939D03*
X687835Y37850D03*
X687345Y46940D03*
X690028Y70142D03*
X688030Y76380D03*
X686891Y115868D03*
X685200Y377820D03*
X684794Y402268D03*
X683187Y413863D03*
X692996Y418358D03*
X694299Y413108D03*
X689269Y410420D03*
X685170Y426600D03*
X690073Y430971D03*
X683175Y433862D03*
X685960Y441530D03*
X690410Y437440D03*
X686044Y450305D03*
X692550Y446730D03*
X686452Y459585D03*
X690323Y481844D03*
X683175Y469862D03*
X690323Y468584D03*
X696242Y474904D03*
X693900Y492100D03*
X687310Y500453D03*
Y522141D03*
X690718Y578913D03*
X694996Y575081D03*
X695249Y768132D03*
X684350Y1448911D03*
X693495Y1519305D03*
X692209Y1620037D03*
X686808Y1643500D03*
X685578Y1637479D03*
X686867Y1651010D03*
X696336Y1668183D03*
X689395Y1665685D03*
X705666Y48010D03*
X697678Y47132D03*
X704201Y72112D03*
X699476Y69982D03*
X699398Y123668D03*
X701171Y130963D03*
X704709Y125586D03*
X707500Y368862D03*
X700300Y382502D03*
X707500Y382362D03*
X709494Y399477D03*
X703500Y401290D03*
X708584Y404868D03*
X700652Y411962D03*
X705652D03*
X705177Y449384D03*
X709927Y490789D03*
X702954Y493038D03*
X701642Y484404D03*
X696652Y497444D03*
X703774Y513463D03*
X708500Y517362D03*
X708210Y537816D03*
X697018Y537577D03*
X700500Y545862D03*
X704500Y555862D03*
X710429Y545752D03*
X708056Y575081D03*
X704056Y583081D03*
X698996D03*
X702806Y613264D03*
X696928Y613207D03*
X705158Y645357D03*
X708418Y650389D03*
X699990Y752266D03*
X699247Y1508062D03*
X699140Y1513772D03*
X707050Y1531700D03*
X709150Y1536250D03*
X703290Y1551700D03*
X707050Y1548400D03*
Y1541800D03*
X703290Y1545100D03*
X708500Y1560500D03*
X699610Y1580523D03*
X708600Y1572523D03*
X710080Y1581683D03*
X710360Y1589296D03*
X702408Y1625027D03*
X709260Y1617903D03*
X705130Y1637501D03*
X707279Y1663644D03*
X714471Y46670D03*
X724621Y40062D03*
X719821Y45862D03*
X714322Y56286D03*
X714096Y73686D03*
X712717Y68541D03*
X719416Y68738D03*
Y74036D03*
X725016Y86952D03*
X720016D03*
X712341Y128093D03*
X723531Y368862D03*
X715500D03*
X717500Y401962D03*
X722613D03*
X720103Y406462D03*
X725142D03*
X714990D03*
X712702Y412200D03*
X719276Y413803D03*
X715632Y487054D03*
X725703Y492990D03*
X720652Y490354D03*
X714810Y493916D03*
X719720Y506438D03*
X716500Y521862D03*
X724500Y517362D03*
X720500Y555862D03*
X718500Y566739D03*
X719710Y612831D03*
X713343Y633842D03*
X724000Y633906D03*
X725812Y654713D03*
X715371Y654726D03*
X715923Y751112D03*
X713020Y1393361D03*
X724110Y1561825D03*
X714900Y1571273D03*
X721440Y1570963D03*
X723590Y1595323D03*
X718892Y1597152D03*
X714372Y1594679D03*
X720106Y1609542D03*
X713718Y1610235D03*
X718129Y1624330D03*
X722889Y1622491D03*
X721525Y1651863D03*
X721665Y1646221D03*
X718360Y1666203D03*
X721632Y1680658D03*
X740101Y41162D03*
X736621Y45262D03*
X733315Y40862D03*
X728721Y43562D03*
X736864Y74943D03*
X731864D03*
X739824Y91052D03*
X734380Y80518D03*
X729380D03*
X736650Y102350D03*
X735771Y94988D03*
X730660Y108484D03*
X729571Y363028D03*
X739500Y368862D03*
X731500D03*
X727500Y386862D03*
X736000Y402330D03*
X732500Y406180D03*
X728377Y402327D03*
X738100Y408780D03*
X730292Y412074D03*
X740757Y414748D03*
X730896Y478953D03*
X736200Y493000D03*
X740172Y489070D03*
X737610Y507479D03*
X732610D03*
X728610Y510479D03*
X727300Y505400D03*
X739185Y521394D03*
X728576Y537476D03*
X736500Y537862D03*
X736647Y529772D03*
X740500Y545862D03*
X738260Y553625D03*
X728714Y554190D03*
X732520Y545988D03*
X736528Y579615D03*
X729452Y576482D03*
X727253Y610689D03*
X730770Y644218D03*
X729720Y742801D03*
X729490Y752266D03*
X734371Y767152D03*
X727138Y1313090D03*
X735739Y1323048D03*
X735271Y1361408D03*
X726475Y1571293D03*
X726550Y1599358D03*
X732976Y1642878D03*
X727679Y1639962D03*
X733760Y1666906D03*
X727242Y1679913D03*
X728454Y1690491D03*
X732852Y1695701D03*
X746101Y46262D03*
X745901Y40362D03*
X747488Y71429D03*
X750701Y106642D03*
X754783Y96553D03*
X741309Y108742D03*
X743050Y139182D03*
X744911Y166887D03*
X751575Y184252D03*
X750560Y268629D03*
X748940Y313588D03*
X746522Y308804D03*
X747594Y319106D03*
X752926Y361021D03*
X755135Y368907D03*
X754813Y374362D03*
X744000Y401090D03*
X747629Y406163D03*
X754000Y403362D03*
X745929Y411963D03*
X746399Y417325D03*
X749990Y492775D03*
X743602Y493134D03*
X755317Y487157D03*
X746850Y487662D03*
X752500Y513362D03*
X753951Y521801D03*
X752965Y537678D03*
X748000Y537862D03*
X752500Y545862D03*
X751776Y564468D03*
X753483Y648749D03*
X754595Y767926D03*
X752554Y1297246D03*
X745634Y1394471D03*
X747150Y1583247D03*
X749167Y1591967D03*
X754635Y1592571D03*
X749261Y1628208D03*
X753770Y1636083D03*
X751521Y1659158D03*
X754030Y1669256D03*
X741925Y1666326D03*
X746766Y1696036D03*
X752187Y1691058D03*
X763221Y65132D03*
X757188Y91829D03*
X757576Y112575D03*
X770073Y143438D03*
X758111Y172636D03*
X762052Y274028D03*
X758510Y298620D03*
X757937Y303908D03*
Y309026D03*
X759500Y402098D03*
X767500Y401470D03*
X770246Y407458D03*
X757258Y408763D03*
X765975Y414414D03*
X769648Y430511D03*
X764446Y433726D03*
X761318Y449344D03*
X761774Y439548D03*
X766057Y451377D03*
X765393Y443989D03*
X763612Y461973D03*
X767891Y466199D03*
X762136Y455634D03*
X770590Y470940D03*
X770094Y478536D03*
X765107Y491745D03*
X769323Y494800D03*
X759555Y491548D03*
X765107Y484299D03*
X758402Y506767D03*
X764500Y513340D03*
X756800Y517050D03*
X760660Y537862D03*
X762779Y570803D03*
X760490Y752266D03*
X767557Y1328009D03*
X766455Y1360780D03*
X758163Y1506538D03*
X766950Y1581233D03*
X757610Y1584023D03*
X761510Y1638434D03*
X762030Y1668583D03*
X757557Y1684444D03*
X767381Y1676594D03*
X768463Y1687769D03*
X768733Y1694485D03*
X771356Y167518D03*
X771427Y158026D03*
X784500Y367500D03*
X775388Y390862D03*
X784498Y396353D03*
X782700Y415284D03*
X771634Y418576D03*
X771277Y413064D03*
X783256Y409340D03*
X783770Y422454D03*
X783821Y431534D03*
X775655Y439075D03*
X780877Y443344D03*
X778659Y453193D03*
X774301Y458788D03*
X783877Y475344D03*
X781541Y486817D03*
X783358Y495344D03*
X771039Y511292D03*
X777166Y504477D03*
X772100Y532700D03*
X781699Y536425D03*
X785500Y544000D03*
X773463Y563455D03*
X784217Y767666D03*
X785520Y1292160D03*
X782115Y1334173D03*
X772770Y1441270D03*
X799226Y328467D03*
X792302Y357537D03*
X795046Y363852D03*
X786571Y403455D03*
X796283Y415344D03*
Y423344D03*
X786877Y443344D03*
X796333Y439344D03*
X786887Y451344D03*
X797463Y476159D03*
X786440Y480769D03*
X786102Y507536D03*
X790503Y501826D03*
X799450Y511801D03*
X800674Y504130D03*
X798276Y531372D03*
X800500Y540500D03*
X799289Y549260D03*
X788941Y561941D03*
X792782Y565323D03*
X799742Y628983D03*
X789895Y752265D03*
X796020Y1292160D03*
X792770Y1411270D03*
Y1426270D03*
X787770Y1441270D03*
X799150Y1581379D03*
X811200Y268624D03*
X802421Y275317D03*
X802300Y284311D03*
X805509Y298850D03*
X807649Y292273D03*
X805391Y307670D03*
X812070Y341590D03*
X805425Y395502D03*
X802270Y435372D03*
X802459Y443218D03*
X802533Y449802D03*
X802752Y459344D03*
X813114Y455344D03*
X812983Y476159D03*
X801874Y471344D03*
X802752Y480159D03*
X801762Y495344D03*
X802752Y487344D03*
X805150Y623843D03*
X805421Y1321257D03*
X801614Y1339062D03*
X811771Y1355488D03*
X810150Y1574633D03*
X810050Y1584033D03*
X820901Y147112D03*
X824653Y405347D03*
X817497Y427060D03*
X816239Y435344D03*
X816117Y443552D03*
X816409Y467568D03*
X830212Y483892D03*
X827000Y489055D03*
X826552Y543612D03*
X823777Y560988D03*
X822883Y780334D03*
X822982Y791245D03*
X822494Y802941D03*
X836780Y68008D03*
X839899Y87248D03*
X841585Y94181D03*
X831298Y104206D03*
X842865Y110296D03*
X835115Y115223D03*
X845221Y135862D03*
Y129362D03*
X837161Y213207D03*
X844527Y204968D03*
X838821Y206872D03*
X837161Y218212D03*
X842539Y301629D03*
Y309306D03*
X834430Y434634D03*
X838000Y423362D03*
X838342Y514610D03*
X841660Y558200D03*
X831505Y897291D03*
X831582Y905153D03*
X844250Y1266759D03*
X838286Y1265305D03*
X837530Y1323420D03*
X833756Y1330156D03*
X840306Y1329303D03*
X833963Y1339464D03*
X838963Y1345974D03*
X841039Y1358082D03*
X839244Y1352094D03*
X841472Y1365050D03*
X850016Y87341D03*
X847473Y94754D03*
X851895Y160141D03*
X856213Y191545D03*
X847581Y232222D03*
X850328Y273557D03*
X849608Y282381D03*
X856244Y286447D03*
X860071Y304850D03*
X851517Y411745D03*
X846000Y423362D03*
X847303Y485788D03*
X849772Y494585D03*
X848097Y503315D03*
X847941Y538325D03*
X855504Y1281729D03*
X856323Y1275530D03*
X846117Y1282182D03*
X856981Y1291726D03*
X856683Y1297228D03*
X846968Y1313869D03*
X850684Y1310000D03*
X858982Y1306000D03*
X847033Y1319000D03*
X850730Y1328519D03*
X850714Y1323491D03*
X850746Y1342000D03*
X847032Y1337388D03*
X847016Y1332041D03*
X850762Y1347090D03*
X852050Y1584033D03*
X874295Y163862D03*
X863488Y176332D03*
X875170Y185113D03*
X867529Y231788D03*
X863104Y273103D03*
X868104D03*
X867701Y267537D03*
X863230Y280001D03*
X866619Y286801D03*
X871099Y323000D03*
X863420Y429362D03*
X860541Y446089D03*
X864361Y493001D03*
X866727Y650739D03*
X870591Y785437D03*
X865394Y801244D03*
X867651Y836820D03*
X865109Y850795D03*
X864768Y844815D03*
X864140Y856052D03*
X864003Y866609D03*
X869638Y1299044D03*
X861020Y1314500D03*
X865337Y1311852D03*
X863827Y1304213D03*
X861757Y1319500D03*
X865000Y1328500D03*
Y1323500D03*
X862498Y1346000D03*
X865333Y1341324D03*
X861000Y1337500D03*
Y1332500D03*
X874989Y1410441D03*
X863745Y1444560D03*
X889351Y195489D03*
X878221Y192055D03*
X881354Y267407D03*
X885764Y284361D03*
X877448Y284825D03*
X888000Y293000D03*
X884410Y794332D03*
X876923Y1239520D03*
X886707Y1235920D03*
X886145Y1270835D03*
X886647Y1299183D03*
X883379Y1417881D03*
X881987Y1449608D03*
X887519Y1444625D03*
X877226Y1441585D03*
X902376Y590172D03*
X903556Y614062D03*
X903941Y893000D03*
X903925Y948500D03*
X900280Y1150769D03*
X896225Y1140635D03*
X891247Y1219520D03*
X896974Y1229869D03*
X892724Y1270516D03*
X893875Y1276116D03*
Y1281216D03*
Y1286316D03*
X893506Y1296599D03*
X893875Y1291316D03*
X900875Y1311355D03*
X898395Y1306920D03*
X903292Y1315822D03*
X904023Y1320892D03*
X900891Y1324898D03*
Y1330005D03*
X900890Y1342808D03*
X896866Y1346000D03*
X904224Y1333843D03*
X900922Y1337725D03*
X894050Y1584033D03*
X894150Y1602633D03*
X917387Y184114D03*
X914575Y560027D03*
X913845Y846656D03*
X907011Y849556D03*
X910500Y863500D03*
X905500D03*
X915000Y893000D03*
Y898000D03*
X909010Y919000D03*
X912425Y941500D03*
X907000D03*
X915575Y948500D03*
X912500Y963309D03*
X907500D03*
X909000Y974000D03*
Y982000D03*
X919779Y1155658D03*
X912053Y1225520D03*
X910707Y1235920D03*
X919691Y1268440D03*
X919725Y1276362D03*
X919128Y1285953D03*
X919721Y1291676D03*
X919784Y1296984D03*
X916415Y1310000D03*
X912371Y1313885D03*
X912387Y1319000D03*
X908892Y1322803D03*
X908894Y1328000D03*
X908889Y1341343D03*
X908912Y1346419D03*
X912211Y1332473D03*
X912222Y1337513D03*
X922128Y182486D03*
X923386Y193563D03*
X920031Y577846D03*
X926449Y577806D03*
X926983Y604751D03*
X920989Y617692D03*
X930926Y664791D03*
X920234Y843349D03*
X927777Y843416D03*
X934129Y844500D03*
X928000Y893000D03*
Y898000D03*
X934500Y926500D03*
X929500D03*
X928500Y941500D03*
X923500D03*
X928500Y956339D03*
X923500Y956304D03*
X927000Y982500D03*
Y977500D03*
X930657Y1103041D03*
X920107Y1229920D03*
X931085Y1268500D03*
X931284Y1276841D03*
X931506Y1285085D03*
X928718Y1300098D03*
X931708Y1293994D03*
X928219Y1308085D03*
X922000Y1324000D03*
X931326Y1328467D03*
X931216Y1323050D03*
X925500Y1333000D03*
X930411Y1347411D03*
X931798Y1670937D03*
X923798D03*
X936454Y184015D03*
X937267Y189010D03*
X945120Y193264D03*
X949181Y280131D03*
X937310Y580755D03*
X939511Y597073D03*
X935746Y611573D03*
X935783Y631192D03*
X945602Y664653D03*
X939216Y664767D03*
X948644Y811190D03*
X941033Y846608D03*
X948000Y862000D03*
X938000Y862620D03*
X943000Y862823D03*
X942500Y926500D03*
X942631Y943162D03*
X936960Y942898D03*
X947207Y979322D03*
X937148Y1134343D03*
X947305Y1150769D03*
X943431Y1140700D03*
X946101Y1219520D03*
X935907Y1239520D03*
X945691Y1235920D03*
X947054Y1268260D03*
X935028Y1313769D03*
X949216Y1448337D03*
X944105Y1448317D03*
X947798Y1670937D03*
X939798D03*
X952798Y165945D03*
X960419Y162294D03*
X952158Y174590D03*
X961407Y205125D03*
X951102Y628662D03*
X951886Y804495D03*
X951466Y816400D03*
X963134Y864000D03*
X956500Y893000D03*
X961500D03*
X950500Y926500D03*
X955865Y983816D03*
X955758Y1144718D03*
X955958Y1229869D03*
X964669Y1271000D03*
X964454Y1287396D03*
X955372Y1311500D03*
X958500Y1306500D03*
X953516Y1305500D03*
X950872Y1314500D03*
Y1319500D03*
X955372Y1328500D03*
Y1323500D03*
X954872Y1346500D03*
Y1341500D03*
X951372Y1337500D03*
Y1332500D03*
X954541Y1448307D03*
X961566Y1448341D03*
X963402Y1501204D03*
X958402D03*
X959584Y1550824D03*
X964774Y173053D03*
X966907Y1225520D03*
X969691Y1235920D03*
X979091Y1229920D03*
X968823Y1267000D03*
X978126Y1268528D03*
X966569Y1282182D03*
X974391Y1295098D03*
X969519Y1452784D03*
X973255Y1456714D03*
X990579Y155248D03*
X988751Y167541D03*
X986447Y158209D03*
X989605Y175400D03*
X985922Y171861D03*
X982455Y260781D03*
Y271443D03*
X984509Y303623D03*
X988460Y358405D03*
X993460D03*
X992460Y370659D03*
X985668Y389311D03*
X980690Y387784D03*
X993650Y465315D03*
X988650D03*
X991270Y470212D03*
X988125Y485193D03*
X994056Y521014D03*
Y516014D03*
Y526074D03*
Y531074D03*
X982665Y1265474D03*
X991823Y1312005D03*
X991500Y1323500D03*
X992000Y1331000D03*
X993500Y1339370D03*
X980779Y1451545D03*
X981768Y1501204D03*
X991196Y1550840D03*
X1002736Y157943D03*
X995181Y157689D03*
X996416Y176579D03*
X1002921Y178799D03*
X1002827Y172479D03*
X1008918Y192994D03*
X1008121Y203525D03*
X1005641Y214969D03*
X997300Y234876D03*
X1006468Y301857D03*
X1003460Y358405D03*
X998460D03*
X1000460Y369535D03*
X996889Y374156D03*
X998359Y451675D03*
X1003909Y454662D03*
Y460162D03*
X996320Y470364D03*
X1002056Y521014D03*
Y516014D03*
Y526074D03*
Y531074D03*
X1002055Y1272690D03*
X1006148Y1283493D03*
X1004483Y1294268D03*
X996988Y1312462D03*
X996848Y1304602D03*
X996000Y1318500D03*
X996500Y1326050D03*
X996000Y1343790D03*
X996500Y1334950D03*
X995936Y1349064D03*
X995000Y1362000D03*
X1005134Y1501204D03*
X1023221Y191574D03*
X1011120Y198114D03*
X1017361Y203109D03*
X1011068Y207667D03*
X1019356Y222423D03*
X1010909Y213708D03*
X1011721Y233699D03*
X1023110Y287311D03*
X1023000Y298311D03*
X1009815Y404896D03*
X1020748Y420902D03*
X1023420Y462921D03*
X1017220Y464155D03*
X1023515Y454397D03*
X1019205Y457687D03*
X1023420Y468039D03*
X1017350Y472155D03*
X1022874Y474545D03*
X1019210Y480155D03*
X1013306Y532501D03*
X1019161Y554757D03*
X1024161D03*
X1017961Y545074D03*
X1014666Y1294268D03*
X1009905Y1305500D03*
X1012500Y1322500D03*
Y1341580D03*
X1013500Y1332740D03*
X1016000Y1361000D03*
X1012500Y1347500D03*
X1022796Y1550840D03*
X1034214Y351601D03*
X1034409Y429618D03*
X1024509Y500168D03*
X1037254Y521014D03*
X1036708Y514883D03*
X1037254Y526074D03*
X1025631Y540104D03*
X1036021Y534990D03*
X1030000Y554500D03*
X1028500Y563000D03*
X1038801Y751765D03*
X1036427Y770532D03*
X1038867Y774960D03*
X1028500Y1501204D03*
X1042015Y444404D03*
X1043991Y540979D03*
X1039407Y547723D03*
X1042628Y556845D03*
X1048684Y1340304D03*
X1051866Y1501204D03*
X1050866Y1659548D03*
X1053290Y1652082D03*
X1045545Y1663089D03*
X1055934Y388988D03*
X1068143Y380188D03*
X1055934Y381988D03*
X1062640Y449155D03*
X1057276Y458155D03*
X1062173Y479655D03*
X1062250Y484672D03*
X1056960Y482262D03*
X1058231Y523238D03*
X1060719Y512359D03*
X1068801Y751765D03*
X1063470Y767665D03*
X1063684Y1340304D03*
X1054396Y1550840D03*
X1063751Y1653834D03*
X1068221Y1662778D03*
X1071698Y270702D03*
X1078400Y391226D03*
X1074654Y380188D03*
X1074249Y387795D03*
X1082866Y403068D03*
X1072738Y411322D03*
Y416763D03*
Y421922D03*
X1077873Y463444D03*
X1071710Y483655D03*
Y488782D03*
X1072232Y667749D03*
X1077034Y1375927D03*
X1075232Y1501204D03*
X1086714Y353515D03*
X1090061Y428019D03*
X1084840Y438234D03*
Y443515D03*
Y460005D03*
X1085851Y465978D03*
X1096473Y484391D03*
Y489391D03*
X1095730Y509362D03*
X1098301Y752265D03*
X1093116Y766369D03*
X1086801Y1297382D03*
X1089934Y1550784D03*
X1097000Y1629500D03*
X1096469Y1643468D03*
X1096768Y1635080D03*
X1087141Y1688914D03*
X1089030Y1717841D03*
Y1722841D03*
X1107300Y456944D03*
X1111076Y464388D03*
X1108076Y646774D03*
X1109634Y1375927D03*
X1099098Y1501204D03*
X1102248Y1496186D03*
X1111701Y1558640D03*
X1100961Y1622543D03*
X1105000Y1682132D03*
X1099108Y1691229D03*
X1121628Y401915D03*
X1121077Y511498D03*
X1120321Y635832D03*
X1127801Y752265D03*
X1122728Y765651D03*
X1119067Y1551457D03*
X1115394Y1620306D03*
X1116000Y1671029D03*
X1122610Y1677976D03*
X1124091Y1683983D03*
X1113948Y1711244D03*
X1142830Y53186D03*
X1142144Y63186D03*
X1129387Y615658D03*
X1138387D03*
X1136301Y1297382D03*
X1142334Y1375927D03*
X1142639Y1562789D03*
X1138480Y1576364D03*
X1132168Y1620860D03*
X1132981Y1634531D03*
X1132209Y1672033D03*
X1151679Y72258D03*
X1157301Y752265D03*
X1145819Y1348254D03*
X1147814Y1562823D03*
X1154336Y1555979D03*
X1149278Y1589453D03*
X1158343Y1658514D03*
X1151985Y1666685D03*
X1152114Y1672517D03*
X1152211Y1682373D03*
X1168687Y74202D03*
X1158764Y489516D03*
X1162067Y570050D03*
X1163485Y1546195D03*
X1161492Y1551175D03*
X1172523Y1573250D03*
X1165806Y1658934D03*
X1159688Y1665427D03*
X1169098Y1666278D03*
X1167228Y1671116D03*
X1169187Y1687117D03*
X1167247Y1680845D03*
X1183354Y77685D03*
X1185913Y93634D03*
X1174031Y403519D03*
X1181000Y402500D03*
X1185952Y432202D03*
Y440202D03*
Y448202D03*
X1178340Y447734D03*
X1185707Y465272D03*
X1186040Y481691D03*
X1182950Y577030D03*
X1178000Y572602D03*
X1182594Y587759D03*
X1178000Y592673D03*
X1182256Y632368D03*
X1188301Y752265D03*
X1185001Y1297382D03*
X1175234Y1375927D03*
X1182305Y1539640D03*
X1184138Y1548524D03*
X1182503Y1555540D03*
X1180087Y1575871D03*
X1178932Y1686698D03*
X1182548Y1679649D03*
Y1674649D03*
X1185676Y1697249D03*
X1198694Y57015D03*
X1191488Y87125D03*
X1200518Y100875D03*
X1200037Y160987D03*
X1189701Y173187D03*
X1201157Y431875D03*
X1193040Y481691D03*
X1199370Y578154D03*
X1195236Y581407D03*
X1195336Y586606D03*
X1191714Y767265D03*
X1194296Y1396500D03*
X1203242Y1417440D03*
X1202548Y1407453D03*
X1202857Y1412454D03*
X1202411Y1427410D03*
X1203117Y1422452D03*
X1202475Y1432468D03*
X1203040Y1437500D03*
X1194000Y1442500D03*
X1190755Y1588978D03*
X1189989Y1605260D03*
X1197980Y1688270D03*
X1189263Y1682551D03*
X1190830Y1675710D03*
X1189462Y1691366D03*
X1197612Y1703334D03*
X1192612D03*
X1196767Y1712261D03*
X1199294Y1721143D03*
X1196814Y1726261D03*
X1208431Y128748D03*
X1215528Y172395D03*
X1214094Y269008D03*
X1213866Y455376D03*
X1208733Y585986D03*
X1204334Y668138D03*
X1210111Y1249357D03*
X1207801Y1348525D03*
X1208034Y1375927D03*
X1211555Y1380511D03*
X1210400Y1440000D03*
X1209721Y1591140D03*
X1207823Y1673581D03*
X1207750Y1688514D03*
X1211135Y1680846D03*
X1212547Y1675898D03*
X1212954Y1703343D03*
X1207954D03*
X1207770Y1717011D03*
X1223455Y91346D03*
X1227803Y94210D03*
X1221411Y134230D03*
X1221512Y128239D03*
X1231118Y142125D03*
X1230094Y269008D03*
X1222094D03*
X1230694Y302716D03*
Y308566D03*
X1218430Y421012D03*
X1221075Y668115D03*
X1229934Y785057D03*
X1230177Y801163D03*
X1228800Y1391300D03*
X1219650Y1392050D03*
X1219500Y1398900D03*
Y1436000D03*
X1220200Y1449100D03*
X1231575Y1579740D03*
X1224170Y1670050D03*
X1219738Y1713861D03*
Y1708861D03*
Y1722861D03*
Y1727861D03*
X1239218Y128239D03*
Y137239D03*
X1247834Y159844D03*
X1246094Y269008D03*
X1238094D03*
X1247785Y295357D03*
X1233468Y419742D03*
X1242429Y443255D03*
X1242692Y483435D03*
X1235177Y788813D03*
X1240177Y801163D03*
X1235177D03*
X1246025Y1329781D03*
X1235400Y1391200D03*
X1238500Y1400900D03*
X1234900Y1404400D03*
X1238200Y1395500D03*
X1235679Y1418908D03*
X1239426Y1591768D03*
X1249152Y72895D03*
X1256064Y101100D03*
X1249065Y241594D03*
Y236594D03*
Y251594D03*
Y246594D03*
X1262094Y269008D03*
X1254094D03*
X1260107Y399125D03*
X1260227Y411128D03*
X1256137Y459182D03*
Y453872D03*
X1248902Y470733D03*
X1257016Y467253D03*
X1275981Y85114D03*
X1269146Y121022D03*
X1263146D03*
X1267037Y180565D03*
X1270094Y269008D03*
X1275585Y393597D03*
X1269840Y411128D03*
X1276980Y1540540D03*
X1272570Y1550910D03*
X1273020Y1545050D03*
X1271640Y1591001D03*
X1263772Y1661154D03*
X1276641D03*
X1287486Y134165D03*
X1278137Y171551D03*
Y184987D03*
X1279447Y213292D03*
X1278094Y269008D03*
X1286094D03*
X1289352Y421950D03*
X1279352Y782824D03*
Y787824D03*
X1281290Y1243712D03*
X1278921Y1329753D03*
X1279525Y1432000D03*
X1287700Y1431700D03*
X1299196Y76209D03*
X1305685Y74748D03*
X1300668Y125739D03*
X1306431Y149330D03*
X1300668Y145739D03*
X1294094Y269008D03*
X1302094D03*
X1304594Y308475D03*
X1293277Y401125D03*
X1296228Y408125D03*
X1302500Y664500D03*
X1294448Y801088D03*
X1299448D03*
X1296000Y1427700D03*
X1301900D03*
X1295700Y1421800D03*
X1300800D03*
X1302390Y1530430D03*
X1295869Y1586934D03*
X1300214Y1662888D03*
X1319667Y87587D03*
Y105227D03*
X1310094Y269008D03*
X1318094D03*
X1316934Y298184D03*
Y303184D03*
X1316266Y564514D03*
X1314194Y1243712D03*
X1311825Y1329696D03*
X1308900Y1525510D03*
X1311767Y1541989D03*
X1311242Y1553193D03*
X1313021Y1548299D03*
X1312700Y1579596D03*
X1319349Y1585567D03*
X1309510Y1588851D03*
X1312014Y1661157D03*
X1327541Y105227D03*
X1337399Y98084D03*
X1326094Y269008D03*
X1334094D03*
X1330820Y525165D03*
Y518265D03*
X1330658Y538749D03*
X1329585Y561806D03*
X1336938Y646221D03*
Y661221D03*
X1337304Y1225023D03*
X1329507Y1228559D03*
X1324293Y1591500D03*
X1323864Y1661179D03*
X1337033Y1661129D03*
X1330473D03*
X1351750Y72826D03*
X1339840Y72860D03*
X1344958Y85358D03*
X1342094Y269008D03*
X1350094D03*
X1346690Y1243769D03*
X1344625Y1329896D03*
X1350188Y1579740D03*
X1344165Y1593174D03*
X1347966Y1661155D03*
X1361550Y67264D03*
X1356868Y85324D03*
X1364369Y120380D03*
X1358094Y269008D03*
X1366094D03*
X1352727Y1214064D03*
X1356196Y1217750D03*
X1369808Y87587D03*
X1377682D03*
X1371259Y98000D03*
X1373862Y511052D03*
X1381457Y511050D03*
X1382123Y614130D03*
X1376312Y623505D03*
X1379438Y646221D03*
X1374261Y709651D03*
X1377207Y1349227D03*
X1369119Y1579775D03*
X1382045Y1700038D03*
X1383715Y236594D03*
Y241594D03*
X1386839Y1595126D03*
X1390102Y1645070D03*
X1385068Y1664907D03*
X1390738Y1664938D03*
X1390179Y1733118D03*
X1411000Y460362D03*
X1409012Y656405D03*
X1406667Y742523D03*
X1405570Y1540510D03*
X1400650Y1550940D03*
X1401200Y1544920D03*
X1403232Y1579519D03*
X1404132Y1588850D03*
X1409286Y1605796D03*
X1400029Y1615796D03*
X1406447Y1619572D03*
X1417000Y460362D03*
X1414823Y647030D03*
X1414157Y670665D03*
X1416289Y1190574D03*
X1422037Y1192848D03*
X1416529Y1313100D03*
X1416327Y1362279D03*
X1411989Y1371140D03*
X1413629Y1393578D03*
X1416862Y1582871D03*
X1419811Y1599084D03*
X1416709Y1592819D03*
X1413836Y1586944D03*
X1418000Y1607500D03*
X1421392Y1621706D03*
X1415622Y1631013D03*
X1421890Y1635500D03*
X1418755Y1654999D03*
X1431262Y61392D03*
X1441612Y688985D03*
X1441757Y775133D03*
X1440714Y841401D03*
X1439586Y1193581D03*
X1426989Y1391140D03*
X1435584Y1596545D03*
X1431981Y1586934D03*
X1438565Y1612583D03*
X1430319Y1623504D03*
X1430238Y1617137D03*
X1429072Y1643655D03*
X1433618Y1659331D03*
X1433157Y1651977D03*
X1438078Y1669992D03*
X1439316Y1675080D03*
X1454769Y163842D03*
X1449769Y174217D03*
X1456500Y457000D03*
X1453564Y537856D03*
X1453177Y563178D03*
X1447423Y679610D03*
X1446757Y703265D03*
X1451352Y848315D03*
X1456352D03*
X1454947Y1193428D03*
X1442045Y1200597D03*
X1448097Y1541990D03*
X1447354Y1553193D03*
X1449133Y1548299D03*
X1447026Y1577299D03*
X1455461Y1585567D03*
X1455312Y1593035D03*
X1455579Y1665701D03*
X1454705Y1671267D03*
X1449551Y1665923D03*
X1466681Y78590D03*
X1462682Y450372D03*
X1456982Y437362D03*
X1461832Y584268D03*
X1465257Y1193188D03*
X1460011Y1196750D03*
X1468357Y1198458D03*
X1463041Y1201640D03*
X1472129Y56083D03*
X1473362Y558380D03*
X1473593Y567449D03*
X1481898Y585476D03*
X1477253Y575751D03*
X1472935Y578344D03*
X1473234Y572437D03*
X1474530Y708562D03*
X1479757Y722865D03*
X1480677Y813488D03*
X1483177Y1193001D03*
X1475597Y1192758D03*
X1480466Y1200046D03*
X1472046Y1592895D03*
X1476416Y1688959D03*
X1486000Y1686000D03*
X1482987Y1690453D03*
X1497386Y464980D03*
X1495682Y473302D03*
X1492514Y539657D03*
X1488510Y542816D03*
X1487660Y585748D03*
X1500500Y809063D03*
X1498177Y829359D03*
X1493821Y1203172D03*
X1495749Y1579740D03*
X1491709Y1593453D03*
X1495874Y1664210D03*
X1488875Y1677385D03*
X1491300Y1730212D03*
X1514576Y219730D03*
X1506865Y546462D03*
X1507644Y554372D03*
X1507468Y564357D03*
X1509757Y575477D03*
X1501821Y577664D03*
X1507612Y708562D03*
X1512757Y722897D03*
X1505287Y789710D03*
X1516114Y1593174D03*
X1529384Y201245D03*
X1519120Y479215D03*
X1527853Y560264D03*
X1518677Y798188D03*
X1523177Y800988D03*
X1527542Y1244837D03*
X1536422Y292816D03*
X1536542Y304819D03*
X1534584Y467067D03*
X1539693Y543613D03*
X1532824Y555981D03*
X1539693Y558943D03*
X1540412Y708562D03*
X1535852Y796138D03*
Y801138D03*
X1543503Y1269314D03*
X1542700Y1540600D03*
X1536770Y1550990D03*
X1537270Y1545020D03*
X1539344Y1579519D03*
X1536893Y1593593D03*
X1556960Y287478D03*
X1551900Y287288D03*
X1548772Y291916D03*
X1551779Y530698D03*
X1546257Y701097D03*
X1556708Y772782D03*
X1553644Y796544D03*
X1560033Y796421D03*
X1548393Y798093D03*
X1551113Y1238088D03*
X1555803Y1276353D03*
X1555852Y1282988D03*
X1560454Y1279004D03*
X1548544Y1297145D03*
X1555222Y1302757D03*
X1557557Y1550574D03*
X1557690Y1542662D03*
X1560043Y1586934D03*
X1569592Y294816D03*
X1572283Y301816D03*
X1564506Y310334D03*
X1572436Y582433D03*
Y574022D03*
X1564785Y611416D03*
X1572759Y611471D03*
X1573749Y686829D03*
X1572588Y762782D03*
X1572182Y792552D03*
X1564553Y801152D03*
X1567737Y1271411D03*
X1569865Y1293656D03*
X1568456Y1311533D03*
X1572416Y1303160D03*
X1564268Y1338440D03*
X1572331Y1348205D03*
X1570040Y1352702D03*
X1561348Y1547217D03*
X1575734Y1541990D03*
X1575416Y1553193D03*
X1574966Y1577038D03*
X1589778Y611456D03*
X1580861Y611440D03*
X1576843Y674425D03*
X1578069Y1256036D03*
X1577630Y1264418D03*
X1584069Y1279706D03*
X1585290Y1285098D03*
X1586110Y1312941D03*
X1580987Y1316110D03*
X1576554Y1338769D03*
X1584156Y1381419D03*
X1586000Y1387641D03*
X1590723Y1381589D03*
X1577195Y1548299D03*
X1583523Y1585567D03*
X1576568Y1590873D03*
X1603970Y222956D03*
X1599837Y295328D03*
X1604890Y531226D03*
X1596299Y536344D03*
X1605618Y731512D03*
X1592188Y739012D03*
X1595355Y792409D03*
X1593237Y1244182D03*
X1595827Y1252679D03*
X1590921Y1309276D03*
X1597621Y1365384D03*
X1592788Y1388318D03*
X1597234Y1382689D03*
X1595046Y1592825D03*
X1619909Y298742D03*
Y293742D03*
X1616198Y556364D03*
X1618859Y542820D03*
X1607369Y561330D03*
X1618356Y609137D03*
X1606312Y652853D03*
X1616801Y752265D03*
X1612597Y1284510D03*
X1629597Y221842D03*
X1631657Y392925D03*
X1622391Y564169D03*
X1635281Y1422450D03*
X1635227Y1436528D03*
X1623811Y1579740D03*
X1623634Y1593871D03*
X1642135Y414202D03*
X1647110Y434177D03*
X1635944Y609510D03*
X1645123Y624478D03*
X1639312Y633853D03*
X1638377Y714972D03*
X1646301Y752265D03*
X1647072Y1323137D03*
X1644001Y1408069D03*
X1646483Y1412741D03*
X1635619Y1430536D03*
X1639834Y1434478D03*
X1636167Y1446746D03*
X1642400Y1439674D03*
X1650400Y1437820D03*
X1641167Y1446746D03*
X1648337Y1451313D03*
X1643158Y1593313D03*
X1645343Y1667718D03*
X1645029Y1715609D03*
Y1710609D03*
Y1725759D03*
Y1730759D03*
X1652525Y141762D03*
X1661110Y389177D03*
Y404177D03*
Y419177D03*
Y434177D03*
X1654110D03*
X1657194Y599956D03*
X1651194D03*
X1657194Y609450D03*
X1651194D03*
X1654147Y616523D03*
X1661017Y670128D03*
X1661317Y689093D03*
X1661007Y700243D03*
X1651214Y765725D03*
X1651301Y1363765D03*
X1660585Y1393660D03*
X1661807Y1416948D03*
X1663777Y1421568D03*
X1658345Y1423124D03*
X1653380Y1657850D03*
X1656101Y1671720D03*
X1651101Y1671833D03*
X1657125Y1661895D03*
X1651698Y1665045D03*
X1653984Y1687051D03*
X1653964Y1676449D03*
X1656101Y1701094D03*
X1673100Y121762D03*
Y136762D03*
X1676110Y389177D03*
Y404177D03*
Y419177D03*
Y434177D03*
X1668516Y599956D03*
X1674516D03*
X1668516Y609450D03*
X1674516D03*
X1676017Y670128D03*
X1676801Y752265D03*
X1670972Y1322837D03*
X1669410Y1421971D03*
X1671079Y1435069D03*
X1666985Y1429651D03*
X1676685Y1537893D03*
X1668027Y1541216D03*
X1671034Y1546934D03*
X1677988Y1561649D03*
X1665750Y1587875D03*
X1676971Y1668582D03*
X1670202Y1663150D03*
X1675290Y1663157D03*
X1668481Y1686259D03*
X1668257Y1679992D03*
X1680029Y1710609D03*
Y1715609D03*
X1670417Y1718373D03*
X1695100Y121762D03*
Y136762D03*
Y131762D03*
Y146762D03*
Y156762D03*
Y161762D03*
Y166762D03*
X1682408Y228337D03*
X1692429Y403985D03*
X1694050Y416643D03*
X1690208Y421855D03*
X1692450Y436772D03*
X1689892Y751674D03*
X1680974Y765871D03*
X1695072Y1322737D03*
X1693367Y1393760D03*
X1681538Y1451522D03*
X1689062Y1451496D03*
X1684172Y1538135D03*
X1686675Y1659287D03*
X1680367Y1663367D03*
X1684733Y1698952D03*
X1695102Y1698947D03*
X1689184Y1702095D03*
X1680877Y1723593D03*
X1702959Y404243D03*
X1697161Y406602D03*
X1707780Y410738D03*
X1695455Y422287D03*
X1707568Y420370D03*
X1701124Y423802D03*
X1707544Y431745D03*
X1699500Y654738D03*
Y673738D03*
X1705801Y752265D03*
X1700868Y766098D03*
X1706850Y1468146D03*
X1709964Y1597490D03*
X1709833Y1612940D03*
Y1606340D03*
X1701984Y1671618D03*
X1695987D03*
X1717148Y19910D03*
X1722085Y25908D03*
X1717055D03*
X1723241Y48822D03*
X1724602Y40966D03*
X1721646Y68115D03*
X1716558Y67866D03*
X1712686Y111908D03*
X1713399Y132858D03*
X1718465Y657982D03*
X1720050Y649142D03*
X1716030Y668182D03*
X1718686Y676154D03*
X1718425Y1468245D03*
X1715693Y1597190D03*
X1719893Y1612940D03*
Y1603040D03*
X1713593Y1609640D03*
Y1603040D03*
X1710170Y1718963D03*
X1719181Y1706712D03*
X1721172Y1712115D03*
X1719218Y1727265D03*
X1719148Y1721530D03*
X1739492Y48971D03*
X1731743Y45001D03*
X1739876Y40742D03*
X1728965Y112941D03*
X1729046Y118178D03*
X1739686Y120938D03*
X1725344Y359334D03*
X1733043Y657091D03*
X1736848Y650974D03*
X1737002Y671494D03*
X1734801Y752265D03*
X1730912Y766977D03*
X1739188Y1478171D03*
X1733065Y1543771D03*
X1726604Y1540970D03*
X1736479Y1584330D03*
X1735463Y1651965D03*
X1730381Y1647386D03*
X1734500Y1656965D03*
X1734962Y1662965D03*
X1734963Y1673465D03*
X1734763Y1680465D03*
X1739315Y1677444D03*
X1731936Y1690165D03*
X1732251Y1708265D03*
X1748708Y26641D03*
X1751031Y39063D03*
X1743491Y92827D03*
X1748686Y97408D03*
X1750786Y120018D03*
X1744976Y122998D03*
X1754339Y128242D03*
X1749169Y206849D03*
X1744510Y377452D03*
X1744380Y382892D03*
X1742306Y661032D03*
X1748062Y1298189D03*
Y1328189D03*
Y1358189D03*
X1743179Y1563578D03*
X1746779Y1583378D03*
X1751558Y1579332D03*
X1750463Y1654465D03*
X1744963Y1656465D03*
X1744463Y1651229D03*
X1751340Y1686140D03*
X1744620Y1716018D03*
X1747120Y1710824D03*
X1765920Y17031D03*
Y22031D03*
X1767266Y48748D03*
X1765527Y53692D03*
X1767956Y76843D03*
X1767136Y83653D03*
X1764644Y122973D03*
X1756606Y228938D03*
X1768041Y556537D03*
X1765301Y752265D03*
X1760246Y767468D03*
X1759388Y1478171D03*
X1769054Y1585705D03*
X1755463Y1654465D03*
X1767888Y1664465D03*
X1765163Y1670543D03*
X1765463Y1677465D03*
X1761463Y1683465D03*
X1770920Y17031D03*
Y22031D03*
X1775920D03*
X1773830Y49000D03*
X1779377Y50738D03*
X1775546Y73376D03*
X1781451Y88238D03*
X1773577Y88339D03*
X1776930Y179051D03*
X1771606Y228938D03*
Y243938D03*
X1770520Y364148D03*
X1782376Y558324D03*
X1783388Y1478171D03*
X1780579Y1582178D03*
X1776785Y1573879D03*
X1787826Y37548D03*
X1792546Y59443D03*
Y74443D03*
X1785108Y76078D03*
X1792546Y89443D03*
X1787756Y85178D03*
X1787390Y156834D03*
X1785320Y193072D03*
X1784915Y186053D03*
X1786606Y228938D03*
Y243938D03*
X1789771Y367866D03*
X1797929Y385293D03*
X1786260Y379059D03*
X1792507Y403932D03*
X1792335Y418775D03*
X1792450Y410615D03*
X1792220Y425432D03*
X1788376Y558324D03*
X1807546Y59443D03*
X1800046Y66943D03*
Y81943D03*
Y96943D03*
X1809595Y180781D03*
X1806470Y186866D03*
X1811274Y198098D03*
X1808429Y218837D03*
X1811606Y226438D03*
X1801606Y243938D03*
X1803129Y362293D03*
X1802929Y385293D03*
X1807388Y1478171D03*
X1818828Y175241D03*
X1817275Y180619D03*
X1816190Y208879D03*
X1816606Y243938D03*
X1819260Y295460D03*
X1820307Y373829D03*
X1828669Y379552D03*
X1820656Y388051D03*
X1820144Y398052D03*
X1819374Y410432D03*
X1818874Y423932D03*
X1822394Y436225D03*
X1828888Y1478171D03*
X1829732Y371329D03*
G54D21*
X36147Y1504577D03*
Y1511577D03*
X42955Y1504577D03*
Y1511577D03*
X70864Y1504487D03*
X77749Y1504524D03*
X70864Y1511487D03*
X77749Y1511524D03*
X70475Y1527169D03*
Y1534169D03*
X78405Y1527169D03*
Y1534169D03*
X97994Y1327151D03*
Y1334151D03*
X112826Y1526634D03*
Y1533634D03*
X104887Y1526568D03*
Y1533568D03*
X112220Y1581306D03*
Y1588306D03*
X125558Y1327168D03*
Y1334168D03*
X117017Y1361811D03*
Y1368811D03*
X125395Y1361811D03*
Y1368811D03*
X117017Y1384054D03*
Y1377054D03*
X133994Y1327251D03*
Y1334251D03*
X157995Y1361811D03*
Y1368811D03*
X149617Y1361811D03*
Y1368811D03*
Y1384054D03*
Y1377054D03*
X170266Y1327168D03*
X162058D03*
X170266Y1334168D03*
X162058D03*
X186682Y1327168D03*
X178474D03*
X186682Y1334168D03*
X178474D03*
X182317Y1361811D03*
Y1368811D03*
Y1384054D03*
Y1377054D03*
X194494Y1327151D03*
Y1334151D03*
X190695Y1361811D03*
Y1368811D03*
X215217Y1361811D03*
Y1368811D03*
Y1384054D03*
Y1377054D03*
X229994Y1327551D03*
Y1334551D03*
X223595Y1361811D03*
Y1368811D03*
X246312Y668330D03*
Y661330D03*
X240711Y694848D03*
Y701848D03*
X238894Y1327551D03*
X247058Y1327568D03*
X238894Y1334551D03*
X247058Y1334568D03*
X248017Y1361811D03*
Y1368811D03*
Y1384054D03*
Y1377054D03*
X253551Y646578D03*
Y653578D03*
X254312Y668330D03*
Y661330D03*
X259157Y694728D03*
Y701728D03*
X249551Y694728D03*
Y701728D03*
X255558Y1327551D03*
Y1334551D03*
X256395Y1361811D03*
Y1368811D03*
X268281Y694728D03*
Y701728D03*
X274621Y726408D03*
Y733408D03*
X271324Y1520453D03*
Y1527453D03*
X286181Y681028D03*
Y688028D03*
X279042Y702371D03*
Y695371D03*
X287042Y702371D03*
Y695371D03*
X281617Y1315665D03*
Y1322665D03*
X289995Y1315665D03*
Y1322665D03*
X281617Y1337908D03*
Y1330908D03*
X278132Y1520453D03*
Y1527453D03*
X285286Y1530646D03*
Y1537646D03*
X302181Y730028D03*
Y737028D03*
X293221Y1280878D03*
Y1287878D03*
X318651Y701078D03*
X311912Y715621D03*
X319912D03*
X318651Y708078D03*
X311912Y722621D03*
X319912D03*
X312051Y749878D03*
Y756878D03*
X320954Y1281194D03*
Y1288194D03*
X314513Y1315637D03*
Y1322637D03*
Y1337880D03*
Y1330880D03*
X327831Y1281208D03*
Y1288208D03*
X322891Y1315637D03*
Y1322637D03*
X344221Y715429D03*
Y722429D03*
X341151Y749878D03*
Y756878D03*
X347417Y1315580D03*
Y1322580D03*
Y1337823D03*
Y1330823D03*
X352599Y700186D03*
Y707186D03*
Y715429D03*
Y722429D03*
X355314Y1281327D03*
X362201Y1281413D03*
X355314Y1288327D03*
X362201Y1288413D03*
X355795Y1315580D03*
Y1322580D03*
X377812Y715221D03*
Y722221D03*
X371551Y749878D03*
Y756878D03*
X380217Y1315780D03*
Y1322780D03*
Y1338023D03*
Y1331023D03*
X385251Y700778D03*
X385812Y715221D03*
X385251Y707778D03*
X385812Y722221D03*
X389701Y1283213D03*
Y1290213D03*
X396176Y1307751D03*
Y1300751D03*
X388595Y1315780D03*
Y1322780D03*
X410712Y697721D03*
Y704721D03*
X409151Y731978D03*
Y738978D03*
X401280Y749563D03*
Y756563D03*
X399386Y1520453D03*
X406194D03*
X399386Y1527453D03*
X406194D03*
X418051Y682878D03*
X418712Y697721D03*
X418051Y689878D03*
X418712Y704721D03*
X424373Y1307868D03*
Y1300868D03*
X421177Y1335111D03*
Y1342111D03*
X412799Y1335111D03*
Y1342111D03*
Y1357354D03*
Y1350354D03*
X421397Y1530646D03*
Y1537646D03*
X436252Y672781D03*
Y679781D03*
X437851Y747958D03*
Y754958D03*
X448090Y131742D03*
Y138742D03*
X450551Y658478D03*
X443112Y672821D03*
X451212D03*
X450551Y665478D03*
X443112Y679821D03*
X451212D03*
X443351Y705949D03*
Y712949D03*
X468912Y653421D03*
Y646421D03*
X462013Y653264D03*
Y646264D03*
X470951Y693378D03*
Y700378D03*
X483251Y631978D03*
Y638978D03*
X475812Y653421D03*
Y646421D03*
X483812Y653421D03*
Y646421D03*
X495279Y612162D03*
Y619162D03*
X516351Y597778D03*
X502112Y612221D03*
X516351Y604778D03*
X509012Y612221D03*
X502112Y619221D03*
X509012D03*
X517012Y612221D03*
Y619221D03*
X517931Y646858D03*
Y653858D03*
X524931Y646858D03*
Y653858D03*
X538851Y646678D03*
Y653678D03*
X531951Y646678D03*
Y653678D03*
X535497Y1520453D03*
X542305D03*
X535497Y1527453D03*
X542305D03*
X549459Y1530646D03*
Y1537646D03*
X678552Y1343988D03*
Y1350988D03*
X706121Y1343988D03*
Y1350988D03*
X724198Y1379230D03*
Y1386230D03*
X724900Y1401346D03*
Y1394346D03*
X735271Y1343988D03*
Y1350988D03*
X732313Y1379230D03*
Y1386230D03*
X766455Y1343360D03*
Y1350360D03*
X756980Y1379330D03*
Y1386330D03*
X765095Y1379330D03*
Y1386330D03*
X757919Y1401446D03*
Y1394446D03*
X779280Y1299759D03*
Y1306759D03*
X771908Y1379184D03*
Y1386184D03*
X795280Y1299759D03*
X787280D03*
X795280Y1306759D03*
X787280D03*
X803280Y1299759D03*
Y1306759D03*
X885823Y1240420D03*
Y1247420D03*
X900923Y1240420D03*
X892823D03*
X900923Y1247420D03*
X892823D03*
X916023Y1240420D03*
X909023D03*
X916023Y1247420D03*
X909023D03*
X944807Y1240420D03*
Y1247420D03*
X951807Y1240420D03*
X959907D03*
X951807Y1247420D03*
X959907D03*
X962000Y1299000D03*
Y1292000D03*
X968580Y208799D03*
Y215799D03*
X968007Y1240420D03*
X975007D03*
X968007Y1247420D03*
X975007D03*
X1069732Y1327132D03*
Y1334132D03*
X1097296Y1327149D03*
Y1334149D03*
X1097133Y1361792D03*
Y1368792D03*
X1088755Y1361792D03*
Y1368792D03*
Y1384035D03*
Y1377035D03*
X1105732Y1327232D03*
Y1334232D03*
X1121355Y1361792D03*
Y1368792D03*
Y1384035D03*
Y1377035D03*
X1141304Y1327149D03*
X1133596D03*
X1141304Y1334149D03*
X1133596D03*
X1129733Y1361792D03*
Y1368792D03*
X1149012Y1327149D03*
X1156720D03*
X1149012Y1334149D03*
X1156720D03*
X1154055Y1361792D03*
Y1368792D03*
Y1384035D03*
Y1377035D03*
X1144420Y1386080D03*
Y1393080D03*
X1166232Y1327132D03*
Y1334132D03*
X1162433Y1361792D03*
Y1368792D03*
X1186955Y1361792D03*
Y1368792D03*
Y1384035D03*
Y1377035D03*
X1201732Y1327532D03*
Y1334532D03*
X1195333Y1361792D03*
Y1368792D03*
X1210632Y1327532D03*
Y1334532D03*
X1227296Y1327532D03*
X1218796Y1327549D03*
X1227296Y1334532D03*
X1218796Y1334549D03*
X1228133Y1361792D03*
Y1368792D03*
X1219755Y1361792D03*
Y1368792D03*
Y1384035D03*
Y1377035D03*
X1257746Y1315646D03*
Y1322646D03*
Y1337889D03*
Y1330889D03*
X1269350Y1280859D03*
Y1287859D03*
X1266124Y1315646D03*
Y1322646D03*
X1290642Y1315618D03*
Y1322618D03*
Y1337861D03*
Y1330861D03*
X1279197Y1553453D03*
X1286005D03*
X1279197Y1560453D03*
X1286005D03*
X1303960Y1281189D03*
X1297083Y1281175D03*
X1303960Y1288189D03*
X1297083Y1288175D03*
X1299020Y1315618D03*
Y1322618D03*
X1293159Y1563646D03*
Y1570646D03*
X1321334Y591261D03*
Y598261D03*
X1313234Y591261D03*
Y598261D03*
X1329376Y591243D03*
Y598243D03*
X1331443Y1281308D03*
Y1288308D03*
X1331924Y1315561D03*
Y1322561D03*
X1323546Y1315561D03*
Y1322561D03*
Y1337804D03*
Y1330804D03*
X1338330Y1281394D03*
Y1288394D03*
X1364034Y616090D03*
Y623090D03*
X1356964Y638394D03*
Y631394D03*
X1364964Y638394D03*
Y631394D03*
X1351930Y664953D03*
Y671953D03*
X1360278Y664953D03*
Y671953D03*
X1365830Y1283194D03*
Y1290194D03*
X1364724Y1315761D03*
Y1322761D03*
X1356346Y1315761D03*
Y1322761D03*
Y1338004D03*
Y1331004D03*
X1368602Y664953D03*
Y671953D03*
X1379644Y671110D03*
Y678110D03*
X1372305Y1307732D03*
Y1300732D03*
X1389664Y671294D03*
Y664294D03*
X1387500Y696943D03*
Y703943D03*
X1388928Y1335092D03*
Y1342092D03*
Y1357335D03*
Y1350335D03*
X1396924Y648980D03*
Y655980D03*
X1397664Y671294D03*
Y664294D03*
X1400502Y1307849D03*
Y1300849D03*
X1397306Y1335092D03*
Y1342092D03*
X1407259Y1553453D03*
Y1560453D03*
X1415044Y703880D03*
X1422264Y703874D03*
Y696874D03*
X1415044Y710880D03*
X1423390Y729673D03*
Y736673D03*
X1414067Y1553453D03*
Y1560453D03*
X1429484Y681610D03*
Y688610D03*
X1430264Y703874D03*
Y696874D03*
X1429271Y1563646D03*
Y1570646D03*
X1454431Y715697D03*
Y722697D03*
X1452334Y749745D03*
Y756745D03*
X1463189Y701204D03*
X1462809Y715697D03*
X1463189Y708204D03*
X1462809Y722697D03*
X1482900Y749440D03*
Y756440D03*
X1495624Y701137D03*
X1496264Y716451D03*
X1488264D03*
X1495624Y708137D03*
X1496264Y723451D03*
X1488264D03*
X1510454Y749787D03*
Y756787D03*
X1528334Y701087D03*
X1521064Y716451D03*
X1529064D03*
X1528334Y708087D03*
X1521064Y723451D03*
X1529064D03*
X1517300Y749770D03*
Y756770D03*
X1543371Y1553453D03*
Y1560453D03*
X1554194Y701511D03*
Y694511D03*
X1552500Y727340D03*
Y734340D03*
X1546047Y767488D03*
Y774488D03*
X1550179Y1553453D03*
X1557333Y1563646D03*
X1550179Y1560453D03*
X1557333Y1570646D03*
X1570394Y670805D03*
Y663805D03*
X1561464Y679157D03*
Y686157D03*
X1562194Y701511D03*
Y694511D03*
X1580067Y667758D03*
Y660758D03*
X1586964Y667742D03*
Y660742D03*
X1587320Y700330D03*
Y707330D03*
X1580154Y727340D03*
Y734340D03*
X1604501Y642232D03*
Y635232D03*
X1594184Y645338D03*
Y652338D03*
X1594964Y667742D03*
Y660742D03*
X1612692Y643297D03*
Y636297D03*
X1614804Y694238D03*
Y701238D03*
X1623059Y592354D03*
Y599354D03*
X1630259Y592315D03*
Y599315D03*
X1627184Y626378D03*
X1627964Y641742D03*
X1627184Y633378D03*
X1619964Y641742D03*
X1627964Y648742D03*
X1619964D03*
X1622300Y675268D03*
Y682268D03*
X1646177Y1342988D03*
Y1349988D03*
X1649854Y675268D03*
Y682268D03*
X1654177Y1342988D03*
Y1349988D03*
X1671931Y1378519D03*
Y1385519D03*
X1672633Y1400635D03*
Y1393635D03*
X1683177Y1342988D03*
Y1349988D03*
X1679931Y1378519D03*
Y1385519D03*
X1704713Y1378619D03*
Y1385619D03*
X1705652Y1400735D03*
Y1393735D03*
X1714198Y1342649D03*
Y1349649D03*
X1712713Y1378619D03*
Y1385619D03*
X1719841Y1378767D03*
Y1385767D03*
X1723110Y1431730D03*
Y1424730D03*
X1744148Y1535580D03*
Y1528580D03*
X1763983Y205965D03*
X1756923Y205902D03*
X1763983Y212965D03*
X1756923Y212902D03*
X1765310Y1559705D03*
Y1566705D03*
X1756904Y1559705D03*
Y1566705D03*
X1772354Y183529D03*
Y190529D03*
X1777864Y211569D03*
Y204569D03*
X1770824Y211559D03*
Y204559D03*
X1783296Y255433D03*
Y262433D03*
X1773352Y1537361D03*
Y1530361D03*
X1791776Y255433D03*
Y262433D03*
X1792179Y1559705D03*
Y1566705D03*
X1799796Y255433D03*
Y262433D03*
X1808422Y1535516D03*
Y1528516D03*
X1800579Y1559705D03*
Y1566705D03*
X1816922Y1535516D03*
Y1528516D03*
G54D30*
X77394Y734588D03*
Y1021399D03*
Y1277698D03*
X107095Y734588D03*
Y1021399D03*
Y1277698D03*
X136795Y734588D03*
Y1021399D03*
Y1277698D03*
X166496Y734588D03*
Y1021399D03*
Y1277698D03*
X196197Y734588D03*
Y1021399D03*
Y1277698D03*
X225898Y734588D03*
Y1021399D03*
Y1277698D03*
X655425Y734588D03*
Y1021399D03*
Y1277698D03*
X685126Y734588D03*
Y1021399D03*
Y1277698D03*
X714827Y734588D03*
Y1021399D03*
Y1277698D03*
X744528Y734588D03*
Y1021399D03*
Y1277698D03*
X774229Y734588D03*
Y1021399D03*
Y1277698D03*
X803929Y734588D03*
Y1021399D03*
Y1277698D03*
X1053536Y734587D03*
Y1021398D03*
Y1277697D03*
X1083237Y734587D03*
Y1021398D03*
Y1277697D03*
X1112937Y734587D03*
Y1021398D03*
Y1277697D03*
X1142638Y734587D03*
Y1021398D03*
Y1277697D03*
X1172339Y734587D03*
Y1021398D03*
Y1277697D03*
X1202040Y734587D03*
Y1021398D03*
Y1277697D03*
X1631567Y734587D03*
Y1021398D03*
Y1277697D03*
X1661268Y734587D03*
Y1021398D03*
Y1277697D03*
X1690969Y734587D03*
Y1021398D03*
Y1277697D03*
X1720670Y734587D03*
Y1021398D03*
Y1277697D03*
X1750371Y734587D03*
Y1021398D03*
Y1277697D03*
X1780071Y734587D03*
Y1021398D03*
Y1277697D03*
G54D12*
X26181Y1457243D03*
Y1482439D03*
X50081Y1457243D03*
Y1482439D03*
X56458Y1497397D03*
Y1522593D03*
X74181Y1457243D03*
Y1482439D03*
X96081Y1457243D03*
Y1482439D03*
X91477Y1497397D03*
Y1522593D03*
X111794Y1325453D03*
Y1350649D03*
X147894Y1325653D03*
Y1350849D03*
X208994Y1325553D03*
Y1350749D03*
X277561Y1279707D03*
Y1304903D03*
X288381Y713164D03*
Y738360D03*
X306983Y1279707D03*
Y1304903D03*
X326951Y733314D03*
Y758510D03*
X341576Y1279622D03*
Y1304818D03*
X356657Y733314D03*
Y758510D03*
X375976Y1279597D03*
Y1304793D03*
X387151Y733280D03*
Y758476D03*
X410661Y1298921D03*
Y1324117D03*
X422951Y715380D03*
Y740576D03*
X457151Y690780D03*
Y715976D03*
X484751Y664214D03*
Y689410D03*
X504611Y664294D03*
Y689490D03*
X692271Y1340890D03*
Y1366086D03*
X720271Y1342520D03*
Y1367716D03*
X752741Y1342430D03*
Y1367626D03*
X1083532Y1325434D03*
Y1350630D03*
X1119632Y1325634D03*
Y1350830D03*
X1180732Y1325534D03*
Y1350730D03*
X1253690Y1279688D03*
Y1304884D03*
X1283112Y1279688D03*
Y1304884D03*
X1317705Y1279603D03*
Y1304799D03*
X1352105Y1279578D03*
Y1304774D03*
X1386790Y1298902D03*
Y1324098D03*
X1401289Y681278D03*
Y706474D03*
X1437261Y713737D03*
Y738933D03*
X1467789Y733482D03*
Y758678D03*
X1496651Y733314D03*
Y758510D03*
X1531030Y733327D03*
Y758523D03*
X1566441Y711374D03*
Y736570D03*
X1601051Y677752D03*
Y702948D03*
X1636101Y658622D03*
Y683818D03*
X1667987Y1341580D03*
Y1366776D03*
X1700467Y1341760D03*
Y1366956D03*
X1727967Y1340380D03*
Y1365576D03*
X1748688Y1483573D03*
Y1508769D03*
X1771388Y1483573D03*
Y1508769D03*
X1758188Y1524433D03*
Y1549629D03*
X1795388Y1483573D03*
Y1508769D03*
X1787093Y1524479D03*
Y1549675D03*
X1819388Y1483573D03*
Y1508769D03*
G54D13*
X36500Y320984D03*
X40000D03*
X46102Y523359D03*
X51253Y1535053D03*
X55503Y758816D03*
X65159Y776888D03*
X66871Y1604274D03*
X53633Y1637880D03*
X58633D03*
X64438Y1661303D03*
X74169Y384676D03*
X92826Y1332539D03*
X86996Y1535053D03*
X103503Y1370698D03*
X98186Y1377021D03*
X103177Y1508862D03*
X124500Y1424984D03*
X136103Y1370698D03*
X130786Y1377021D03*
X130000Y1424984D03*
X168803Y1370698D03*
X163486Y1377021D03*
X183021Y1542196D03*
X182813Y1671980D03*
X182517Y1702215D03*
X201703Y1370698D03*
X196386Y1377021D03*
X207660Y1671662D03*
X203660Y1678662D03*
X207807Y1686779D03*
Y1701897D03*
X203807Y1693779D03*
X207807Y1708897D03*
X229186Y1377021D03*
X238063Y34237D03*
X233203Y752064D03*
X234503Y1370698D03*
X268971Y802672D03*
X268103Y1324552D03*
X262786Y1330875D03*
X282716Y45849D03*
X287671Y1524106D03*
X283671D03*
X297520Y18221D03*
X297315Y585938D03*
X300999Y1324524D03*
X295682Y1330847D03*
X311716Y45849D03*
X307716D03*
X311083Y1542196D03*
X333903Y1324467D03*
X328586Y1330790D03*
X362157Y546399D03*
Y553399D03*
X361386Y1330990D03*
X366703Y1324667D03*
X385443Y594787D03*
X389443D03*
X381443D03*
X393371Y969472D03*
X393968Y1350321D03*
X397657Y580399D03*
X399285Y1343998D03*
X408000Y1638984D03*
X422048Y117844D03*
X423921Y1009407D03*
X415733Y1524106D03*
X411733D03*
X433226Y114489D03*
X425548Y117844D03*
X429726Y114489D03*
X437710Y245649D03*
X438882Y1009407D03*
X435141D03*
X427661D03*
X431401D03*
X430691Y1306228D03*
X432000Y1646484D03*
X448890Y113491D03*
X452890D03*
X451710Y244649D03*
X441710Y245649D03*
X447710Y244649D03*
X446362Y1009407D03*
X450102D03*
X442622D03*
X453842D03*
X441159Y1054750D03*
X447194Y1542196D03*
X457582Y1009407D03*
X461186Y1638934D03*
X461000Y1646984D03*
X499576Y130882D03*
X487271Y969472D03*
X503576Y130882D03*
X514576Y131482D03*
X508670Y147529D03*
X504670D03*
X504618Y166632D03*
X508618D03*
X519091Y125191D03*
Y132191D03*
X523091D03*
X539120Y37046D03*
X535117Y37019D03*
X542723Y37060D03*
X534876Y126973D03*
X538876D03*
X544680Y140477D03*
X543026Y253597D03*
X553620Y37246D03*
X549919Y37146D03*
X548610Y54719D03*
X548680Y140477D03*
X547844Y1524106D03*
X551844D03*
X589444Y71145D03*
X579771Y803372D03*
X583671Y803472D03*
X575256Y1542196D03*
X594444Y71145D03*
X602334Y67827D03*
X595571Y796672D03*
X599471D03*
X601771Y1272757D03*
X616815Y67827D03*
X610315D03*
X606263D03*
X607671Y785872D03*
X611671D03*
X605771Y1272757D03*
X622007Y72232D03*
X632800Y754084D03*
X628800D03*
X643146Y36970D03*
X647258Y1696754D03*
Y1703754D03*
X643258Y1710754D03*
X647258Y1717754D03*
X656286Y36970D03*
X662863Y58434D03*
X658735Y58423D03*
X651258Y1700604D03*
Y1714604D03*
X674963Y33226D03*
X670964D03*
X678291Y55166D03*
X670500Y387846D03*
X675500Y396346D03*
X680621Y33226D03*
X692466Y41434D03*
X685838Y33204D03*
X682291Y54306D03*
X686291Y55666D03*
X681500Y119984D03*
X683500Y396346D03*
X679500D03*
X691500D03*
X687560D03*
X683398Y1650134D03*
X697893Y41434D03*
X693954Y128011D03*
X707500Y396346D03*
X703500D03*
X695500D03*
X699500D03*
X707800Y525546D03*
X705742Y1395030D03*
X719950Y55029D03*
X714666Y94617D03*
X722666D03*
X718666D03*
X710666D03*
X714703Y383860D03*
X723500Y396346D03*
X721909Y528236D03*
X714845Y528408D03*
X711059Y1388707D03*
X721950Y1583842D03*
X721890Y1604721D03*
X709317Y1627270D03*
X713317Y1637770D03*
X717422Y1648821D03*
X713771Y1660449D03*
X715927Y1682188D03*
X721632Y1677367D03*
X737596Y55029D03*
X733643D03*
X724645D03*
X729294D03*
X735457Y383712D03*
X735500Y396346D03*
X731500D03*
X730152Y440328D03*
X736439Y500828D03*
X737610Y515138D03*
X738524Y1395130D03*
X727242Y1676553D03*
X749478Y55029D03*
X745475D03*
X741378D03*
X753036Y312729D03*
Y305729D03*
X747500Y383846D03*
X751500D03*
X743457Y383712D03*
X739457D03*
X743500Y396346D03*
X739652Y396328D03*
X751500Y396346D03*
X751972Y500940D03*
X744439Y500828D03*
X740439D03*
X748007Y501224D03*
X743841Y1388807D03*
X757038Y317244D03*
X755500Y396346D03*
X767500D03*
X760652Y500828D03*
X756652D03*
X764152D03*
X762350Y1584292D03*
X768500Y543346D03*
X781000Y569484D03*
X783974Y458862D03*
X785500Y532484D03*
X805450Y1587092D03*
X833445Y226202D03*
X847450Y1587092D03*
X862528Y267866D03*
X901000Y915484D03*
X889450Y1587092D03*
X917377Y884938D03*
X917000Y915484D03*
X916763Y989841D03*
X905487Y1141381D03*
X929603Y885405D03*
X918000Y924984D03*
X925500Y913484D03*
X929500Y922984D03*
X919500Y947984D03*
X946500Y913484D03*
X942500Y922984D03*
X938500Y913484D03*
X934500Y922984D03*
X932500Y947984D03*
X943798Y1666246D03*
X948000Y858484D03*
X949500Y876484D03*
X956500Y899484D03*
X961500D03*
X954500Y913484D03*
X950500Y922984D03*
X952512Y1141381D03*
X951798Y1658204D03*
X963500Y860484D03*
X967500Y1297484D03*
X1013306Y523630D03*
X1021911Y203112D03*
X1063968Y1332693D03*
X1075241Y1370679D03*
X1069924Y1377002D03*
X1107841Y1370679D03*
X1102524Y1377002D03*
X1122965Y1640287D03*
X1126000Y1678484D03*
X1140541Y1370679D03*
X1135224Y1377002D03*
X1129500Y1638484D03*
Y1678484D03*
X1147947Y1678889D03*
X1152000Y1678984D03*
X1168124Y1377002D03*
X1173441Y1370679D03*
X1190894Y1575196D03*
X1206241Y1370679D03*
X1200924Y1377002D03*
X1226094Y311625D03*
X1222094Y302625D03*
X1226094D03*
X1225934Y780366D03*
X1229934D03*
X1225500Y1411484D03*
X1244232Y1324533D03*
X1238915Y1330856D03*
X1231000Y1411484D03*
X1257177Y804308D03*
X1253177D03*
X1264177D03*
X1273177D03*
X1271811Y1330828D03*
X1277128Y1324505D03*
X1304715Y1330771D03*
X1291544Y1557106D03*
X1295544D03*
X1310032Y1324448D03*
X1318956Y1575196D03*
X1329477Y1218862D03*
X1348421Y1190111D03*
X1337977Y1218862D03*
X1342832Y1324648D03*
X1337515Y1330971D03*
X1352421Y1190111D03*
X1369677Y969472D03*
X1375414Y1343979D03*
X1370097Y1350302D03*
X1400063Y1009406D03*
X1403803D03*
X1407543D03*
X1405686Y1306242D03*
X1415024Y1009406D03*
X1422504D03*
X1411283D03*
X1418764D03*
X1417301Y1054749D03*
X1423606Y1557106D03*
X1419606D03*
X1426244Y1009406D03*
X1429984D03*
X1433724D03*
X1463177Y969472D03*
X1455068Y1575196D03*
X1469832Y540886D03*
X1475257Y543961D03*
X1481177Y808972D03*
X1474177Y822472D03*
X1498543Y585349D03*
X1494543D03*
X1493177Y808972D03*
X1485177D03*
X1486177Y822472D03*
X1490177D03*
X1510757Y570961D03*
X1502543Y585349D03*
X1504000Y808972D03*
X1502177Y822472D03*
X1535512Y1238415D03*
X1556111Y804171D03*
X1555718Y1557106D03*
X1559917Y804161D03*
X1565502Y1344668D03*
X1568906Y1359162D03*
X1559718Y1557106D03*
X1574000Y568484D03*
X1580924Y1351682D03*
X1581181Y1376357D03*
X1586000Y1376360D03*
X1578599Y1396916D03*
X1583411D03*
X1588099D03*
X1583130Y1575196D03*
X1595355Y800268D03*
X1590827Y1260338D03*
X1594827D03*
X1595438Y1376270D03*
X1590723Y1376350D03*
X1599657Y1376325D03*
X1592788Y1396916D03*
X1597674D03*
X1629826Y1424425D03*
X1658792Y1387996D03*
X1653475Y1394319D03*
X1691574Y1388096D03*
X1686257Y1394419D03*
X1689383Y1726652D03*
Y1719652D03*
X1693383Y1723502D03*
X1713173Y34228D03*
X1720462Y76589D03*
X1724462D03*
X1727429Y1675440D03*
X1731429D03*
X1741519Y1574569D03*
X1766062Y43087D03*
X1760929Y1654440D03*
X1769757Y34384D03*
X1774279Y1568089D03*
X1791645Y190881D03*
X1797994Y182503D03*
X1801979Y1533889D03*
G54D22*
X48575Y386993D03*
X48742Y393408D03*
X48828Y528304D03*
X48966Y533985D03*
X41117Y1598896D03*
X48151Y1625405D03*
X65412Y443677D03*
X55259Y1589981D03*
Y1585981D03*
X53617Y1612696D03*
X82117Y1625396D03*
Y1620896D03*
Y1616396D03*
X83843Y767766D03*
Y771366D03*
X90874Y960966D03*
X89984Y1417000D03*
Y1412500D03*
Y1408000D03*
Y1426000D03*
Y1421500D03*
Y1430500D03*
Y1440000D03*
X101143Y751766D03*
X103544Y767266D03*
X98984Y1412500D03*
Y1421500D03*
Y1426000D03*
Y1430500D03*
Y1440000D03*
Y1435500D03*
X113544Y767766D03*
Y771366D03*
X120575Y960966D03*
X129643Y751766D03*
X133245Y767266D03*
X133159Y1680513D03*
X143376Y767400D03*
Y771200D03*
X150275Y960966D03*
X159143Y751766D03*
X162884Y767266D03*
X173046Y767666D03*
Y771266D03*
X179976Y960966D03*
X200643Y751266D03*
X188643Y751766D03*
X192646Y767266D03*
X201165Y1652454D03*
Y1648454D03*
X202777Y767400D03*
X202746Y771366D03*
X209677Y960966D03*
X222247Y767266D03*
X232117Y583948D03*
X235347Y767766D03*
Y771366D03*
X251955Y772388D03*
Y776388D03*
X277755Y801888D03*
X285235Y804048D03*
X298625Y37420D03*
X348484Y578500D03*
Y582500D03*
X356641Y550415D03*
Y554415D03*
Y566415D03*
X365067Y590479D03*
X356641Y590415D03*
Y586415D03*
X361695Y1193918D03*
Y1187862D03*
X361755Y1202388D03*
X373415Y1199648D03*
X373375Y1211538D03*
X391255Y981766D03*
X389319Y978266D03*
X391755Y1000266D03*
Y987766D03*
X391655Y994488D03*
X391643Y1007266D03*
X389590Y1015474D03*
X389643Y1010766D03*
X389590Y1019017D03*
Y1022560D03*
X382755Y1207488D03*
X385701Y1677874D03*
X400641Y557415D03*
Y561415D03*
Y565415D03*
Y569415D03*
X400755Y966488D03*
X406255Y981766D03*
X400619Y978266D03*
X398755Y981766D03*
X399255Y987766D03*
X398655Y994488D03*
X406755Y987766D03*
X398655Y1000266D03*
X397143Y1010766D03*
X404643D03*
X410143Y1007266D03*
X397070Y1015474D03*
X404550D03*
X397070Y1019017D03*
X404550D03*
X409643Y1028266D03*
X397070Y1022560D03*
X404550D03*
X409643Y1034266D03*
X401755Y1071988D03*
X402484Y1626800D03*
X407490Y1631219D03*
X423255Y966488D03*
X423143Y978266D03*
X413755Y981766D03*
X421255D03*
X413755Y987766D03*
X420729Y987761D03*
X418650Y1006123D03*
Y1009864D03*
Y1013604D03*
Y1021084D03*
Y1028564D03*
Y1017344D03*
Y1024824D03*
X424143Y1060266D03*
X424255Y1071988D03*
X412960Y1610161D03*
X412987Y1615400D03*
X416984Y1657500D03*
X432785Y120209D03*
Y124209D03*
Y132297D03*
Y128297D03*
X428755Y981766D03*
X428100Y1014766D03*
X437925Y1014745D03*
Y1023013D03*
Y1018879D03*
X428082Y1023013D03*
Y1018879D03*
X439984Y1641500D03*
Y1646500D03*
X454755Y969988D03*
X441643Y989766D03*
X441568Y997766D03*
Y993766D03*
Y1001766D03*
X446783Y1014745D03*
Y1023013D03*
Y1018879D03*
X462516Y112039D03*
Y108039D03*
X467755Y966488D03*
X467143Y978266D03*
X457019Y1014745D03*
Y1023013D03*
Y1018879D03*
X468643Y1060266D03*
X455755Y1068488D03*
X468755Y1071988D03*
X481052Y281093D03*
X480143Y1060266D03*
X491482Y285893D03*
X490355Y1060288D03*
X514905Y124498D03*
X507410Y140498D03*
X508616Y157898D03*
Y153898D03*
X530075Y129207D03*
Y133207D03*
X547364Y144493D03*
Y148493D03*
Y160493D03*
Y164493D03*
Y156493D03*
Y152493D03*
X572045Y1234075D03*
X572065Y1238165D03*
X572841Y1252788D03*
X572085Y1245965D03*
Y1242105D03*
X564639Y1245927D03*
X584643Y1234075D03*
X576330Y1261913D03*
X591643Y1238075D03*
X605643Y1241575D03*
X616255Y1266988D03*
X616265Y1278668D03*
X622029Y55682D03*
X627079Y51682D03*
X625266Y65173D03*
X631117Y1368752D03*
X625104Y1388057D03*
X619700Y1379093D03*
X641206Y53747D03*
X641129Y70040D03*
Y66040D03*
X647328Y439518D03*
X646154Y461930D03*
X647401Y479141D03*
X648474Y751266D03*
X650923Y64745D03*
X650891Y68572D03*
X658788Y444497D03*
X659484Y457862D03*
Y469862D03*
Y465862D03*
X651813Y767266D03*
X662006Y767300D03*
Y771100D03*
X660451Y1641522D03*
X653451D03*
X657301Y1637522D03*
X669464Y210362D03*
Y206362D03*
Y202362D03*
X675482Y404646D03*
X675496Y413863D03*
X675505Y409222D03*
X675556Y422000D03*
X675509Y473362D03*
X677974Y751766D03*
X678556Y1684739D03*
X690984Y497000D03*
X681514Y767266D03*
X691707Y767300D03*
Y771100D03*
X680445Y1633042D03*
Y1637042D03*
X679881Y1650419D03*
X692454Y1662341D03*
X692457Y1658331D03*
X685394Y1684760D03*
X696536Y502534D03*
X707474Y751766D03*
X705742Y1631036D03*
X711215Y767266D03*
X721408Y767300D03*
Y771100D03*
X723234Y1590753D03*
X721176Y1628911D03*
Y1632961D03*
X732511Y582036D03*
X736974Y751766D03*
X728575Y1643997D03*
X752147Y76029D03*
X741984Y564000D03*
X742187Y569245D03*
X742040Y573171D03*
X751108Y767300D03*
X740916Y767266D03*
X751108Y771100D03*
X778136Y423344D03*
Y463344D03*
Y479344D03*
Y475344D03*
Y471344D03*
X780836Y483344D03*
X778436Y491644D03*
X778136Y499344D03*
Y495344D03*
X770736Y499344D03*
X770617Y767266D03*
X780809Y767300D03*
Y771100D03*
X793309Y456518D03*
Y460518D03*
X792636Y479344D03*
Y483344D03*
X788977Y487524D03*
X797379Y751765D03*
X797359Y1345923D03*
X802004Y144262D03*
Y139262D03*
X810048Y276820D03*
X810102Y284311D03*
X800875Y308062D03*
X809163Y504261D03*
X800317Y767266D03*
X804230Y1345878D03*
X826055Y288063D03*
X823328Y476159D03*
X814198Y1486876D03*
Y1490876D03*
Y1496876D03*
Y1500876D03*
Y1506284D03*
Y1516284D03*
Y1510284D03*
Y1520284D03*
X849966Y291559D03*
X852715Y301542D03*
X852874Y308852D03*
X852365Y1273971D03*
X852279Y1278139D03*
X852440Y1291468D03*
X852404Y1295981D03*
X857987Y273557D03*
X892691Y1145058D03*
X901067Y1268420D03*
X901111Y1272692D03*
X900986Y1281203D03*
X901034Y1276968D03*
X900777Y1298027D03*
X900738Y1293853D03*
X901010Y1289630D03*
X901032Y1285420D03*
X905484Y853000D03*
X915484Y945000D03*
X931409Y197612D03*
X925838Y1266347D03*
X925914Y1283048D03*
X926066Y1278713D03*
X925939Y1274591D03*
X925988Y1270408D03*
X926070Y1295957D03*
X925993Y1291676D03*
X926015Y1287193D03*
X921484Y1302000D03*
Y1306000D03*
X937984Y850500D03*
X944984Y894500D03*
X939716Y1145058D03*
X956984Y903500D03*
X960984Y1283000D03*
Y1287000D03*
X957007Y1505777D03*
Y1509777D03*
X997353Y1267126D03*
X1008324Y1275768D03*
X1008403Y1279751D03*
X1008353Y1271743D03*
X1014211Y1290096D03*
X1046785Y751265D03*
X1049924Y767265D03*
X1060116Y767299D03*
Y771099D03*
X1077285Y751765D03*
X1079625Y767265D03*
X1067016Y960965D03*
X1089817Y767299D03*
Y771099D03*
X1105785Y751765D03*
X1109325Y767265D03*
X1096717Y960965D03*
X1119518Y767299D03*
Y771099D03*
X1118198Y1649513D03*
X1135285Y751765D03*
X1139026Y767265D03*
X1126417Y960965D03*
X1136484Y1679000D03*
X1149219Y767299D03*
Y771099D03*
X1143580Y1673937D03*
X1164785Y751765D03*
X1168727Y767265D03*
X1156118Y960965D03*
X1176785Y751265D03*
X1178919Y767299D03*
Y771099D03*
X1198428Y767265D03*
X1185819Y960965D03*
X1190984Y1396500D03*
Y1401000D03*
X1199984D03*
X1190984Y1414500D03*
Y1405500D03*
Y1410000D03*
X1199984D03*
Y1414500D03*
Y1419000D03*
Y1424000D03*
X1211489Y767665D03*
Y771465D03*
X1296459Y134409D03*
X1307150Y537303D03*
X1336661Y1207988D03*
Y1211488D03*
X1355661Y1207988D03*
X1377161Y966488D03*
X1376761Y978265D03*
X1367661Y981765D03*
X1375161D03*
X1365461Y978265D03*
X1367661Y1000265D03*
X1375061D03*
X1367661Y987765D03*
X1374661Y994265D03*
X1367661D03*
X1375161Y987765D03*
X1373212Y1015473D03*
X1365785Y1010765D03*
X1373285D03*
X1365732Y1015473D03*
X1367785Y1007265D03*
X1365732Y1022559D03*
Y1019016D03*
X1373212D03*
Y1022559D03*
X1366661Y1060265D03*
X1369161Y1056765D03*
X1378161Y1071988D03*
X1382661Y981765D03*
X1390161D03*
X1389661Y987765D03*
X1382661D03*
X1380692Y1015473D03*
X1386285Y1007265D03*
X1380785Y1010765D03*
X1380692Y1019016D03*
Y1022559D03*
X1385785Y1028265D03*
Y1034265D03*
X1399161Y966488D03*
X1397661Y981765D03*
X1404661D03*
X1399285Y978265D03*
X1396861Y987765D03*
X1394792Y1013603D03*
Y1006122D03*
X1404224Y1014744D03*
X1394792Y1009863D03*
Y1017343D03*
Y1021083D03*
Y1024823D03*
X1404224Y1018878D03*
X1394792Y1028563D03*
X1404224Y1023012D03*
X1400285Y1060265D03*
X1400161Y1071988D03*
X1417710Y993765D03*
X1417785Y989765D03*
X1417710Y997765D03*
X1414067Y1014744D03*
X1422925D03*
X1417710Y1001765D03*
X1422925Y1018878D03*
X1414067Y1023012D03*
Y1018878D03*
X1422925Y1023012D03*
X1418153Y1641431D03*
X1411082Y1641405D03*
X1409873Y1649720D03*
X1416995Y1649716D03*
X1430661Y969988D03*
X1433161Y1014744D03*
Y1023012D03*
Y1018878D03*
X1431961Y1068488D03*
X1449011Y531318D03*
X1448511Y561318D03*
X1446771Y847652D03*
X1452787Y843652D03*
X1443661Y966488D03*
X1443285Y978265D03*
X1444785Y1060265D03*
X1444661Y1071988D03*
X1466585Y1060265D03*
X1469741Y544977D03*
Y556977D03*
X1479167Y581658D03*
X1469741Y580977D03*
Y576977D03*
Y568977D03*
Y572977D03*
X1513741Y547977D03*
Y551977D03*
Y555977D03*
Y559977D03*
X1531161Y797688D03*
Y801488D03*
X1567747Y1237662D03*
X1561161Y1234162D03*
X1562691Y1290418D03*
Y1293918D03*
X1570161Y1286108D03*
X1579287Y1235366D03*
X1586287Y1239866D03*
X1585431Y1264488D03*
Y1260588D03*
X1602661Y1282988D03*
Y1290988D03*
Y1298988D03*
Y1294988D03*
X1609030Y1307553D03*
X1624285Y752765D03*
X1627955Y767265D03*
X1638147D03*
Y771065D03*
X1653785Y753265D03*
X1657656Y767265D03*
X1667848D03*
Y771065D03*
X1690409Y118762D03*
X1680759Y131762D03*
X1690409D03*
Y126762D03*
Y122762D03*
X1680759Y136762D03*
X1690409Y141762D03*
Y136762D03*
Y149762D03*
Y145762D03*
Y157762D03*
Y166762D03*
X1684785Y753265D03*
X1687357Y767265D03*
X1697549D03*
Y771065D03*
X1716247Y43654D03*
Y39654D03*
Y51654D03*
Y47654D03*
X1713285Y752765D03*
X1717058Y767265D03*
X1727250Y767299D03*
Y771099D03*
X1729913Y1654456D03*
Y1681456D03*
X1742785Y752765D03*
X1746759Y767265D03*
X1756950Y767305D03*
Y771105D03*
X1772785Y753265D03*
X1776459Y767265D03*
X1772349Y1669037D03*
X1770947Y1661465D03*
X1771147Y1672965D03*
X1786651Y767565D03*
Y771365D03*
X1814106Y170869D03*
G54D31*
X99729Y289822D03*
Y310256D03*
X757184Y1722772D03*
X1072863Y1429176D03*
X1080970Y1660958D03*
X1299439Y92812D03*
X1550377Y581353D03*
G54D40*
X360649Y558332D03*
X361000Y568790D03*
X1473784Y553086D03*
G54D50*
X434401Y971551D03*
X1410543Y971550D03*
G54D14*
X36500Y318017D03*
X40000D03*
X46102Y520392D03*
X51253Y1532086D03*
X55503Y755849D03*
X65159Y773921D03*
X66871Y1601307D03*
X53633Y1634913D03*
X58633D03*
X64438Y1658336D03*
X74169Y381709D03*
X92826Y1329572D03*
X86996Y1532086D03*
X103503Y1367731D03*
X98186Y1374054D03*
X103177Y1505895D03*
X124500Y1422017D03*
X136103Y1367731D03*
X130786Y1374054D03*
X130000Y1422017D03*
X168803Y1367731D03*
X163486Y1374054D03*
X183021Y1539229D03*
X182813Y1669013D03*
X182517Y1699248D03*
X201703Y1367731D03*
X196386Y1374054D03*
X207660Y1668695D03*
X203660Y1675695D03*
X207807Y1683812D03*
Y1698930D03*
X203807Y1690812D03*
X207807Y1705930D03*
X229186Y1374054D03*
X238063Y31270D03*
X233203Y749097D03*
X234503Y1367731D03*
X268971Y799705D03*
X268103Y1321585D03*
X262786Y1327908D03*
X282716Y42882D03*
X287671Y1521139D03*
X283671D03*
X297520Y15254D03*
X297315Y582971D03*
X295682Y1327880D03*
X300999Y1321557D03*
X311716Y42882D03*
X307716D03*
X311083Y1539229D03*
X328586Y1327823D03*
X333903Y1321500D03*
X362157Y543432D03*
Y550432D03*
X361386Y1328023D03*
X366703Y1321700D03*
X385443Y591820D03*
X389443D03*
X381443D03*
X393371Y966505D03*
X393968Y1347354D03*
X397657Y577432D03*
X399285Y1341031D03*
X408000Y1636017D03*
X422048Y114877D03*
X423921Y1006440D03*
X415733Y1521139D03*
X411733D03*
X433226Y111522D03*
X425548Y114877D03*
X429726Y111522D03*
X437710Y242682D03*
X438882Y1006440D03*
X435141D03*
X427661D03*
X431401D03*
X430691Y1303261D03*
X432000Y1643517D03*
X448890Y110524D03*
X452890D03*
X451710Y241682D03*
X441710Y242682D03*
X447710Y241682D03*
X446362Y1006440D03*
X450102D03*
X442622D03*
X453842D03*
X441159Y1051783D03*
X447194Y1539229D03*
X457582Y1006440D03*
X461186Y1635967D03*
X461000Y1644017D03*
X499576Y127915D03*
X487271Y966505D03*
X503576Y127915D03*
X514576Y128515D03*
X508670Y144562D03*
X504670D03*
X504618Y163665D03*
X508618D03*
X519091Y122224D03*
Y129224D03*
X523091D03*
X539120Y34079D03*
X535117Y34052D03*
X542723Y34093D03*
X534876Y124006D03*
X538876D03*
X544680Y137510D03*
X543026Y250630D03*
X553620Y34279D03*
X549919Y34179D03*
X548610Y51752D03*
X548680Y137510D03*
X547844Y1521139D03*
X551844D03*
X589444Y68178D03*
X579771Y800405D03*
X583671Y800505D03*
X575256Y1539229D03*
X594444Y68178D03*
X602334Y64860D03*
X595571Y793705D03*
X599471D03*
X601771Y1269790D03*
X616815Y64860D03*
X610315D03*
X606263D03*
X607671Y782905D03*
X611671D03*
X605771Y1269790D03*
X622007Y69265D03*
X632800Y751117D03*
X628800D03*
X643146Y34003D03*
X647258Y1700787D03*
Y1693787D03*
Y1714787D03*
X643258Y1707787D03*
X656286Y34003D03*
X662863Y55467D03*
X658735Y55456D03*
X651258Y1697637D03*
Y1711637D03*
X674963Y30259D03*
X670964D03*
X678291Y52199D03*
X670500Y384879D03*
X675500Y393379D03*
X680621Y30259D03*
X685838Y30237D03*
X692466Y38467D03*
X682291Y51339D03*
X686291Y52699D03*
X681500Y117017D03*
X683500Y393379D03*
X679500D03*
X691500D03*
X687560D03*
X683398Y1647167D03*
X697893Y38467D03*
X693954Y125044D03*
X707500Y393379D03*
X703500D03*
X695500D03*
X699500D03*
X707800Y522579D03*
X705742Y1392063D03*
X719950Y52062D03*
X714666Y91650D03*
X722666D03*
X718666D03*
X710666D03*
X714703Y380893D03*
X723500Y393379D03*
X721909Y525269D03*
X714845Y525441D03*
X711059Y1385740D03*
X721950Y1580875D03*
X721890Y1601754D03*
X709317Y1624303D03*
X713317Y1634803D03*
X717422Y1645854D03*
X713771Y1657482D03*
X715927Y1679221D03*
X721632Y1674400D03*
X737596Y52062D03*
X733643D03*
X724645D03*
X729294D03*
X735457Y380745D03*
X735500Y393379D03*
X731500D03*
X730152Y437361D03*
X736439Y497861D03*
X737610Y512171D03*
X738524Y1392163D03*
X727242Y1673586D03*
X749478Y52062D03*
X745475D03*
X741378D03*
X753036Y309762D03*
Y302762D03*
X747500Y380879D03*
X751500D03*
X743457Y380745D03*
X739457D03*
X743500Y393379D03*
X739652Y393361D03*
X751500Y393379D03*
X751972Y497973D03*
X744439Y497861D03*
X740439D03*
X748007Y498257D03*
X743841Y1385840D03*
X757038Y314277D03*
X755500Y393379D03*
X767500D03*
X760652Y497861D03*
X756652D03*
X764152D03*
X762350Y1581325D03*
X768500Y540379D03*
X781000Y566517D03*
X783974Y455895D03*
X785500Y529517D03*
X805450Y1584125D03*
X833445Y223235D03*
X847450Y1584125D03*
X862528Y264899D03*
X901000Y912517D03*
X889450Y1584125D03*
X917377Y881971D03*
X917000Y912517D03*
X916763Y986874D03*
X905487Y1138414D03*
X929603Y882438D03*
X925500Y910517D03*
X918000Y922017D03*
X929500Y920017D03*
X919500Y945017D03*
X946500Y910517D03*
X938500D03*
X942500Y920017D03*
X934500D03*
X932500Y945017D03*
X943798Y1663279D03*
X948000Y855517D03*
X949500Y873517D03*
X956500Y896517D03*
X961500D03*
X954500Y910517D03*
X950500Y920017D03*
X952512Y1138414D03*
X951798Y1655237D03*
X963500Y857517D03*
X967500Y1294517D03*
X1013306Y520663D03*
X1021911Y200145D03*
X1063968Y1329726D03*
X1075241Y1367712D03*
X1069924Y1374035D03*
X1107841Y1367712D03*
X1102524Y1374035D03*
X1122965Y1637320D03*
X1126000Y1675517D03*
X1140541Y1367712D03*
X1135224Y1374035D03*
X1129500Y1635517D03*
Y1675517D03*
X1147947Y1675922D03*
X1152000Y1676017D03*
X1168124Y1374035D03*
X1173441Y1367712D03*
X1190894Y1572229D03*
X1206241Y1367712D03*
X1200924Y1374035D03*
X1222094Y299658D03*
X1226094D03*
Y308658D03*
X1225934Y777399D03*
X1229934D03*
X1225500Y1408517D03*
X1244232Y1321566D03*
X1238915Y1327889D03*
X1231000Y1408517D03*
X1257177Y801341D03*
X1253177D03*
X1264177D03*
X1273177D03*
X1271811Y1327861D03*
X1277128Y1321538D03*
X1304715Y1327804D03*
X1291544Y1554139D03*
X1295544D03*
X1310032Y1321481D03*
X1318956Y1572229D03*
X1329477Y1215895D03*
X1348421Y1187144D03*
X1337977Y1215895D03*
X1337515Y1328004D03*
X1342832Y1321681D03*
X1352421Y1187144D03*
X1369677Y966505D03*
X1375414Y1341012D03*
X1370097Y1347335D03*
X1400063Y1006439D03*
X1403803D03*
X1407543D03*
X1405686Y1303275D03*
X1415024Y1006439D03*
X1422504D03*
X1411283D03*
X1418764D03*
X1417301Y1051782D03*
X1423606Y1554139D03*
X1419606D03*
X1426244Y1006439D03*
X1429984D03*
X1433724D03*
X1463177Y966505D03*
X1455068Y1572229D03*
X1469832Y537919D03*
X1475257Y540994D03*
X1481177Y806005D03*
X1474177Y819505D03*
X1498543Y582382D03*
X1494543D03*
X1493177Y806005D03*
X1485177D03*
X1486177Y819505D03*
X1490177D03*
X1510757Y567994D03*
X1502543Y582382D03*
X1504000Y806005D03*
X1502177Y819505D03*
X1535512Y1235448D03*
X1556111Y801204D03*
X1555718Y1554139D03*
X1559917Y801194D03*
X1565502Y1341701D03*
X1568906Y1356195D03*
X1559718Y1554139D03*
X1574000Y565517D03*
X1580924Y1348715D03*
X1581181Y1373390D03*
X1586000Y1373393D03*
X1578599Y1393949D03*
X1583411D03*
X1588099D03*
X1583130Y1572229D03*
X1595355Y797301D03*
X1590827Y1257371D03*
X1594827D03*
X1595438Y1373303D03*
X1590723Y1373383D03*
X1599657Y1373358D03*
X1592788Y1393949D03*
X1597674D03*
X1629826Y1421458D03*
X1658792Y1385029D03*
X1653475Y1391352D03*
X1691574Y1385129D03*
X1686257Y1391452D03*
X1689383Y1716685D03*
Y1723685D03*
X1693383Y1720535D03*
X1713173Y31261D03*
X1720462Y73622D03*
X1724462D03*
X1727429Y1672473D03*
X1731429D03*
X1741519Y1571602D03*
X1766062Y40120D03*
X1760929Y1651473D03*
X1769757Y31417D03*
X1774279Y1565122D03*
X1791645Y187914D03*
X1797994Y179536D03*
X1801979Y1530922D03*
G54D23*
X45608Y386993D03*
X45775Y393408D03*
X45861Y528304D03*
X45999Y533985D03*
X52292Y1589981D03*
Y1585981D03*
X38150Y1598896D03*
X45184Y1625405D03*
X50650Y1612696D03*
X62445Y443677D03*
X80876Y767766D03*
Y771366D03*
X79150Y1625396D03*
Y1620896D03*
Y1616396D03*
X87907Y960966D03*
X87017Y1417000D03*
Y1412500D03*
Y1408000D03*
X96017Y1412500D03*
X87017Y1426000D03*
Y1421500D03*
X96017D03*
Y1426000D03*
Y1430500D03*
X87017D03*
Y1440000D03*
X96017D03*
Y1435500D03*
X98176Y751766D03*
X110577Y767766D03*
X100577Y767266D03*
X110577Y771366D03*
X126676Y751766D03*
X117608Y960966D03*
X140409Y767400D03*
X130278Y767266D03*
X140409Y771200D03*
X130192Y1680513D03*
X156176Y751766D03*
X147308Y960966D03*
X170079Y767666D03*
X159917Y767266D03*
X170079Y771266D03*
X185676Y751766D03*
X177009Y960966D03*
X197676Y751266D03*
X199810Y767400D03*
X189679Y767266D03*
X199779Y771366D03*
X198198Y1652454D03*
Y1648454D03*
X206710Y960966D03*
X229150Y583948D03*
X219280Y767266D03*
X232380Y767766D03*
Y771366D03*
X248988Y772388D03*
Y776388D03*
X274788Y801888D03*
X282268Y804048D03*
X295658Y37420D03*
X345517Y578500D03*
Y582500D03*
X353674Y550415D03*
Y554415D03*
Y566415D03*
X362100Y590479D03*
X353674Y590415D03*
Y586415D03*
X358728Y1193918D03*
Y1187862D03*
X358788Y1202388D03*
X379788Y1207488D03*
X370448Y1199648D03*
X370408Y1211538D03*
X388288Y981766D03*
X386352Y978266D03*
X388788Y1000266D03*
Y987766D03*
X388688Y994488D03*
X394176Y1010766D03*
X388676Y1007266D03*
X386623Y1015474D03*
X394103D03*
X386676Y1010766D03*
X394103Y1019017D03*
X386623D03*
Y1022560D03*
X394103D03*
X382734Y1677874D03*
X397674Y557415D03*
Y561415D03*
Y565415D03*
Y569415D03*
X397788Y966488D03*
X403288Y981766D03*
X397652Y978266D03*
X395788Y981766D03*
X396288Y987766D03*
X395688Y994488D03*
X403788Y987766D03*
X395688Y1000266D03*
X401676Y1010766D03*
X407176Y1007266D03*
X401583Y1015474D03*
Y1019017D03*
X406676Y1028266D03*
X401583Y1022560D03*
X406676Y1034266D03*
X398788Y1071988D03*
X409993Y1610161D03*
X410020Y1615400D03*
X399517Y1626800D03*
X404523Y1631219D03*
X420288Y966488D03*
X420176Y978266D03*
X410788Y981766D03*
X418288D03*
X410788Y987766D03*
X417762Y987761D03*
X415683Y1006123D03*
X425133Y1014766D03*
X415683Y1009864D03*
Y1013604D03*
Y1021084D03*
Y1028564D03*
Y1017344D03*
X425115Y1023013D03*
X415683Y1024824D03*
X425115Y1018879D03*
X421176Y1060266D03*
X421288Y1071988D03*
X414017Y1657500D03*
X429818Y120209D03*
Y124209D03*
Y132297D03*
Y128297D03*
X425788Y981766D03*
X438676Y989766D03*
X438601Y997766D03*
Y993766D03*
X434958Y1014745D03*
X438601Y1001766D03*
X434958Y1023013D03*
Y1018879D03*
X437017Y1641500D03*
Y1646500D03*
X451788Y969988D03*
X454052Y1014745D03*
X443816D03*
Y1023013D03*
X454052D03*
Y1018879D03*
X443816D03*
X452788Y1068488D03*
X459549Y112039D03*
Y108039D03*
X464788Y966488D03*
X464176Y978266D03*
X465676Y1060266D03*
X465788Y1071988D03*
X478085Y281093D03*
X477176Y1060266D03*
X488515Y285893D03*
X487388Y1060288D03*
X511938Y124498D03*
X504443Y140498D03*
X505649Y157898D03*
Y153898D03*
X527108Y129207D03*
Y133207D03*
X544397Y144493D03*
Y148493D03*
Y160493D03*
Y164493D03*
Y156493D03*
Y152493D03*
X569078Y1234075D03*
X569098Y1238165D03*
X569874Y1252788D03*
X569118Y1245965D03*
Y1242105D03*
X561672Y1245927D03*
X573363Y1261913D03*
X588676Y1238075D03*
X581676Y1234075D03*
X602676Y1241575D03*
X619062Y55682D03*
X613288Y1266988D03*
X613298Y1278668D03*
X616733Y1379093D03*
X624112Y51682D03*
X622299Y65173D03*
X628150Y1368752D03*
X622137Y1388057D03*
X638239Y53747D03*
X638162Y70040D03*
Y66040D03*
X647956Y64745D03*
X647924Y68572D03*
X644361Y439518D03*
X643187Y461930D03*
X644434Y479141D03*
X645507Y751266D03*
X648846Y767266D03*
X655821Y444497D03*
X656517Y457862D03*
Y469862D03*
Y465862D03*
X659039Y767300D03*
Y771100D03*
X657484Y1641522D03*
X650484D03*
X654334Y1637522D03*
X666497Y210362D03*
Y206362D03*
Y202362D03*
X672515Y404646D03*
X672529Y413863D03*
X672538Y409222D03*
X672589Y422000D03*
X672542Y473362D03*
X675007Y751766D03*
X678547Y767266D03*
X677478Y1633042D03*
Y1637042D03*
X676914Y1650419D03*
X675589Y1684739D03*
X693569Y502534D03*
X688017Y497000D03*
X688740Y767300D03*
Y771100D03*
X689487Y1662341D03*
X689490Y1658331D03*
X682427Y1684760D03*
X704507Y751766D03*
X708248Y767266D03*
X702775Y1631036D03*
X718441Y767300D03*
Y771100D03*
X720267Y1590753D03*
X718209Y1628911D03*
Y1632961D03*
X729544Y582036D03*
X734007Y751766D03*
X737949Y767266D03*
X725608Y1643997D03*
X749180Y76029D03*
X739017Y564000D03*
X739220Y569245D03*
X739073Y573171D03*
X748141Y767300D03*
Y771100D03*
X767769Y499344D03*
X767650Y767266D03*
X775169Y423344D03*
Y463344D03*
Y479344D03*
Y475344D03*
Y471344D03*
X777869Y483344D03*
X775469Y491644D03*
X775169Y499344D03*
Y495344D03*
X777842Y767300D03*
Y771100D03*
X797908Y308062D03*
X790342Y456518D03*
Y460518D03*
X789669Y479344D03*
Y483344D03*
X786010Y487524D03*
X794412Y751765D03*
X797350Y767266D03*
X794392Y1345923D03*
X799037Y144262D03*
Y139262D03*
X807081Y276820D03*
X807135Y284311D03*
X806196Y504261D03*
X801263Y1345878D03*
X811231Y1486876D03*
Y1490876D03*
Y1496876D03*
Y1500876D03*
Y1506284D03*
Y1516284D03*
Y1510284D03*
Y1520284D03*
X823088Y288063D03*
X820361Y476159D03*
X855020Y273557D03*
X846999Y291559D03*
X849748Y301542D03*
X849907Y308852D03*
X849398Y1273971D03*
X849312Y1278139D03*
X849473Y1291468D03*
X849437Y1295981D03*
X902517Y853000D03*
X889724Y1145058D03*
X898100Y1268420D03*
X898144Y1272692D03*
X898019Y1281203D03*
X898067Y1276968D03*
X897810Y1298027D03*
X897771Y1293853D03*
X898043Y1289630D03*
X898065Y1285420D03*
X912517Y945000D03*
X928442Y197612D03*
X922871Y1266347D03*
X922947Y1283048D03*
X923099Y1278713D03*
X922972Y1274591D03*
X923021Y1270408D03*
X923103Y1295957D03*
X923026Y1291676D03*
X923048Y1287193D03*
X918517Y1302000D03*
Y1306000D03*
X935017Y850500D03*
X942017Y894500D03*
X936749Y1145058D03*
X954017Y903500D03*
X958017Y1283000D03*
Y1287000D03*
X954040Y1505777D03*
Y1509777D03*
X994386Y1267126D03*
X1005357Y1275768D03*
X1005436Y1279751D03*
X1005386Y1271743D03*
X1011244Y1290096D03*
X1043818Y751265D03*
X1046957Y767265D03*
X1057149Y767299D03*
Y771099D03*
X1064049Y960965D03*
X1074318Y751765D03*
X1076658Y767265D03*
X1086850Y767299D03*
Y771099D03*
X1093750Y960965D03*
X1102818Y751765D03*
X1106358Y767265D03*
X1116551Y767299D03*
Y771099D03*
X1123450Y960965D03*
X1115231Y1649513D03*
X1132318Y751765D03*
X1136059Y767265D03*
X1140613Y1673937D03*
X1133517Y1679000D03*
X1146252Y767299D03*
Y771099D03*
X1153151Y960965D03*
X1161818Y751765D03*
X1165760Y767265D03*
X1173818Y751265D03*
X1175952Y767299D03*
Y771099D03*
X1182852Y960965D03*
X1195461Y767265D03*
X1188017Y1396500D03*
Y1401000D03*
X1197017D03*
X1188017Y1414500D03*
Y1405500D03*
Y1410000D03*
X1197017D03*
Y1414500D03*
Y1419000D03*
Y1424000D03*
X1208522Y767665D03*
Y771465D03*
X1293492Y134409D03*
X1304183Y537303D03*
X1333694Y1207988D03*
Y1211488D03*
X1362494Y978265D03*
X1362818Y1010765D03*
X1362765Y1015473D03*
Y1022559D03*
Y1019016D03*
X1363694Y1060265D03*
X1352694Y1207988D03*
X1374194Y966488D03*
X1373794Y978265D03*
X1364694Y981765D03*
X1372194D03*
X1364694Y1000265D03*
X1372094D03*
X1364694Y987765D03*
X1371694Y994265D03*
X1364694D03*
X1372194Y987765D03*
X1370245Y1015473D03*
X1377725D03*
X1370318Y1010765D03*
X1377818D03*
X1364818Y1007265D03*
X1377725Y1019016D03*
X1370245D03*
Y1022559D03*
X1377725D03*
X1366194Y1056765D03*
X1375194Y1071988D03*
X1379694Y981765D03*
X1387194D03*
X1393894Y987765D03*
X1386694D03*
X1379694D03*
X1391825Y1013603D03*
X1383318Y1007265D03*
X1391825Y1006122D03*
Y1009863D03*
Y1017343D03*
Y1021083D03*
Y1024823D03*
X1382818Y1028265D03*
X1391825Y1028563D03*
X1382818Y1034265D03*
X1396194Y966488D03*
X1394694Y981765D03*
X1401694D03*
X1396318Y978265D03*
X1401257Y1014744D03*
Y1018878D03*
Y1023012D03*
X1397318Y1060265D03*
X1397194Y1071988D03*
X1408115Y1641405D03*
X1406906Y1649720D03*
X1414743Y993765D03*
X1414818Y989765D03*
X1414743Y997765D03*
X1411100Y1014744D03*
X1419958D03*
X1414743Y1001765D03*
X1419958Y1018878D03*
X1411100Y1023012D03*
Y1018878D03*
X1419958Y1023012D03*
X1415186Y1641431D03*
X1414028Y1649716D03*
X1427694Y969988D03*
X1430194Y1014744D03*
Y1023012D03*
Y1018878D03*
X1428994Y1068488D03*
X1446044Y531318D03*
X1445544Y561318D03*
X1443804Y847652D03*
X1449820Y843652D03*
X1440694Y966488D03*
X1440318Y978265D03*
X1441818Y1060265D03*
X1441694Y1071988D03*
X1466774Y544977D03*
Y556977D03*
Y580977D03*
Y576977D03*
Y568977D03*
Y572977D03*
X1463618Y1060265D03*
X1476200Y581658D03*
X1510774Y547977D03*
Y551977D03*
Y555977D03*
Y559977D03*
X1528194Y797688D03*
Y801488D03*
X1558194Y1234162D03*
X1564780Y1237662D03*
X1559724Y1290418D03*
Y1293918D03*
X1567194Y1286108D03*
X1576320Y1235366D03*
X1583320Y1239866D03*
X1582464Y1264488D03*
Y1260588D03*
X1599694Y1282988D03*
Y1290988D03*
Y1298988D03*
Y1294988D03*
X1606063Y1307553D03*
X1621318Y752765D03*
X1624988Y767265D03*
X1635180D03*
Y771065D03*
X1650818Y753265D03*
X1654689Y767265D03*
X1664881D03*
Y771065D03*
X1687442Y118762D03*
X1677792Y131762D03*
X1687442D03*
Y126762D03*
Y122762D03*
X1677792Y136762D03*
X1687442Y141762D03*
Y136762D03*
Y149762D03*
Y145762D03*
Y157762D03*
Y166762D03*
X1681818Y753265D03*
X1684390Y767265D03*
X1694582D03*
Y771065D03*
X1713280Y43654D03*
Y39654D03*
Y51654D03*
Y47654D03*
X1710318Y752765D03*
X1714091Y767265D03*
X1724283Y767299D03*
Y771099D03*
X1726946Y1654456D03*
Y1681456D03*
X1739818Y752765D03*
X1743792Y767265D03*
X1753983Y767305D03*
Y771105D03*
X1769818Y753265D03*
X1773492Y767265D03*
X1769382Y1669037D03*
X1767980Y1661465D03*
X1768180Y1672965D03*
X1783684Y767565D03*
Y771365D03*
X1811139Y170869D03*
G54D32*
X169288Y1506640D03*
X171388D03*
X169288Y1516140D03*
X171388D03*
X169288Y1522540D03*
X171388D03*
X169288Y1512940D03*
X171388D03*
X169288Y1519340D03*
X171388D03*
X169288Y1509840D03*
X171388D03*
X177763Y1523820D03*
X179863D03*
X172765Y1625407D03*
X174865D03*
X172765Y1628707D03*
X174865D03*
X202631Y1638154D03*
X204731D03*
X202631Y1641454D03*
X204731D03*
X274750Y1507400D03*
X266473Y1526648D03*
X264373D03*
X276850Y1507400D03*
X297350Y1510800D03*
X299450D03*
X292350D03*
X294450D03*
X297350Y1518040D03*
X299450D03*
X292350D03*
X294450D03*
X297350Y1514420D03*
X299450D03*
X292350D03*
X294450D03*
X305825Y1523820D03*
X307925D03*
X394535Y1526648D03*
X392435D03*
X402812Y1507400D03*
X404912D03*
X433461Y1510800D03*
X435561D03*
X428461D03*
X430561D03*
X433461Y1518040D03*
X435561D03*
X428461D03*
X430561D03*
X433461Y1514420D03*
X435561D03*
X428461D03*
X430561D03*
X441936Y1523820D03*
X444036D03*
X441947Y1528728D03*
X444047D03*
X528546Y1526648D03*
X538923Y1507400D03*
X541023D03*
X530646Y1526648D03*
X556523Y1510800D03*
X558623D03*
X556523Y1518040D03*
X558623D03*
X556523Y1514420D03*
X558623D03*
X561523Y1510800D03*
X563623D03*
X561523Y1518040D03*
X563623D03*
X561523Y1514420D03*
X563623D03*
X569998Y1523820D03*
X572098D03*
X617950Y1641600D03*
Y1638400D03*
X620050Y1641600D03*
Y1638400D03*
X628602Y1635949D03*
X630702D03*
X644448Y1642896D03*
X642348D03*
X638610Y1650639D03*
X636510D03*
X663453Y1509072D03*
X665553D03*
X841950Y1315000D03*
Y1319000D03*
Y1333000D03*
Y1337000D03*
X853950Y1306000D03*
X856050D03*
X853950Y1310000D03*
X856050D03*
X847050D03*
X844950D03*
X847050Y1306000D03*
X844950D03*
X847050Y1302000D03*
X844950D03*
X853950D03*
X856050D03*
X844050Y1315000D03*
Y1319000D03*
X855950D03*
Y1315000D03*
X847750Y1324000D03*
X845650D03*
X847750Y1328000D03*
X845650D03*
X855950Y1337000D03*
Y1333000D03*
X847750Y1342000D03*
X845650D03*
X844050Y1333000D03*
Y1337000D03*
X847750Y1346000D03*
X845650D03*
X858050Y1319000D03*
Y1315000D03*
X857450Y1324000D03*
X859550D03*
X857450Y1328000D03*
X859550D03*
X858050Y1337000D03*
Y1333000D03*
X857450Y1342000D03*
X859550D03*
X857450Y1346000D03*
X859550D03*
X887450Y1307500D03*
X889550D03*
X907950Y1302000D03*
X910050D03*
X907950Y1306000D03*
X910050D03*
Y1310000D03*
X907950D03*
X903850Y1328000D03*
X905950D03*
X907150Y1319000D03*
X909250D03*
X903850Y1324000D03*
X905950D03*
X907150Y1315000D03*
X909250D03*
X916950Y1324000D03*
Y1328000D03*
X903850Y1342000D03*
X905950D03*
X907150Y1337000D03*
X909250D03*
X907150Y1333000D03*
X909250D03*
X916950Y1342000D03*
X903850Y1346000D03*
X905950D03*
X916950D03*
X919450Y1310000D03*
X921550D03*
X919450Y1315000D03*
X921550D03*
X919450Y1319000D03*
X921550D03*
X919050Y1324000D03*
Y1328000D03*
Y1342000D03*
X919450Y1337000D03*
X921550D03*
X919450Y1333000D03*
X921550D03*
X919050Y1346000D03*
X942550Y1309500D03*
X940450D03*
X942550Y1305000D03*
X940450D03*
X942550Y1301500D03*
X940450D03*
X938450Y1328000D03*
X940550D03*
X938450Y1323500D03*
X940550D03*
X938450Y1314500D03*
X940550D03*
X938450Y1319000D03*
X940550D03*
X945550Y1314500D03*
X943450D03*
X945550Y1319000D03*
X943450D03*
X945550Y1323500D03*
X943450D03*
X945550Y1328000D03*
X943450D03*
X938450Y1337000D03*
X940550D03*
X938450Y1341500D03*
X940550D03*
X938450Y1332500D03*
X940550D03*
X945550D03*
X943450D03*
X945550Y1337000D03*
X943450D03*
X945550Y1341500D03*
X943450D03*
X938450Y1346000D03*
X940550D03*
X945550D03*
X943450D03*
X948322Y1309500D03*
X950422D03*
X948322Y1305500D03*
X950422D03*
X948322Y1301500D03*
X950422D03*
X966550Y1304200D03*
X968650D03*
X966550Y1307400D03*
X968650D03*
X977450Y1307500D03*
X979550D03*
X1006450Y1310500D03*
X1001450D03*
X1003550D03*
X1001450Y1303000D03*
X1003550D03*
X1001450Y1307000D03*
X1003550D03*
X1006450Y1315000D03*
Y1323840D03*
Y1319420D03*
Y1328260D03*
X1001450D03*
X1003550D03*
X1001450Y1323840D03*
X1003550D03*
X1001450Y1319420D03*
X1003550D03*
X1001450Y1315000D03*
X1003550D03*
X1006450Y1337160D03*
Y1332740D03*
Y1341580D03*
X1001450D03*
X1003550D03*
X1001450Y1332740D03*
X1003550D03*
X1001450Y1337160D03*
X1003550D03*
X1006450Y1346000D03*
X1001450D03*
X1003550D03*
X1008550Y1310500D03*
Y1315000D03*
Y1323840D03*
Y1319420D03*
Y1328260D03*
Y1337160D03*
Y1332740D03*
Y1341580D03*
Y1346000D03*
X1162009Y1669759D03*
X1164109D03*
X1161950Y1678500D03*
X1164050D03*
X1161950Y1673000D03*
X1164050D03*
X1161950Y1682000D03*
X1164050D03*
X1177161Y1542840D03*
X1179261D03*
X1177161Y1539640D03*
X1179261D03*
X1177161Y1552340D03*
X1179261D03*
X1177161Y1545940D03*
X1179261D03*
X1177161Y1549140D03*
X1179261D03*
X1177161Y1555540D03*
X1179261D03*
X1177826Y1682132D03*
X1175726D03*
X1185636Y1556820D03*
X1187736D03*
X1185518Y1675192D03*
X1187618D03*
X1185476Y1679128D03*
X1187576D03*
X1207750Y1685400D03*
X1209850D03*
X1201404D03*
X1203504D03*
X1201404Y1679000D03*
X1203504D03*
X1201404Y1675800D03*
X1203504D03*
X1201404Y1682200D03*
X1203504D03*
X1274346Y1559648D03*
X1272246D03*
X1282623Y1540400D03*
X1284723D03*
X1300223Y1551040D03*
X1302323D03*
X1300223Y1547420D03*
X1302323D03*
X1300223Y1543800D03*
X1302323D03*
X1305223Y1547420D03*
X1307323D03*
X1305223Y1543800D03*
X1307323D03*
X1305223Y1551040D03*
X1307323D03*
X1313698Y1556820D03*
X1315798D03*
X1402408Y1559648D03*
X1400308D03*
X1410685Y1540400D03*
X1412785D03*
X1436335Y1551040D03*
X1438435D03*
X1436335Y1547420D03*
X1438435D03*
X1436335Y1543800D03*
X1438435D03*
X1441335Y1547420D03*
X1443435D03*
X1441335Y1543800D03*
X1443435D03*
X1441335Y1551040D03*
X1443435D03*
X1449810Y1556820D03*
X1451910D03*
X1444232Y1667625D03*
X1446332D03*
X1449087Y1670759D03*
X1451187D03*
X1439292Y1665444D03*
X1441392D03*
X1453950Y1679000D03*
X1456050D03*
X1538520Y1559648D03*
X1536420D03*
X1546797Y1540400D03*
X1548897D03*
X1564397Y1551040D03*
X1566497D03*
X1569397Y1547420D03*
X1571497D03*
X1569397Y1543800D03*
X1571497D03*
X1564397Y1547420D03*
X1566497D03*
X1564397Y1543800D03*
X1566497D03*
X1569397Y1551040D03*
X1571497D03*
X1577872Y1556820D03*
X1579972D03*
X1658406Y1655648D03*
X1656306D03*
X1662305Y1662555D03*
X1660205D03*
X1649111Y1683441D03*
X1651211D03*
X1649066Y1680312D03*
X1651166D03*
X1648909Y1676470D03*
X1651009D03*
X1648552Y1687728D03*
X1650652D03*
X1661125Y1688021D03*
X1671327Y1542072D03*
X1673427D03*
X1663225Y1688021D03*
G54D41*
X365338Y567553D03*
Y565978D03*
Y564403D03*
Y562828D03*
Y561254D03*
Y578576D03*
Y577002D03*
Y575427D03*
Y573852D03*
Y572277D03*
Y570702D03*
Y569128D03*
X387976Y561254D03*
Y562828D03*
Y564403D03*
Y565978D03*
Y567553D03*
Y569128D03*
Y570702D03*
Y572277D03*
Y573852D03*
Y575427D03*
Y577002D03*
Y578576D03*
X1478438Y551816D03*
Y567564D03*
Y565989D03*
Y564414D03*
Y562839D03*
Y561264D03*
Y559690D03*
Y558115D03*
Y556540D03*
Y554965D03*
Y553390D03*
Y569138D03*
X1501076Y551816D03*
Y553390D03*
Y554965D03*
Y556540D03*
Y558115D03*
Y559690D03*
Y561264D03*
Y562839D03*
Y564414D03*
Y565989D03*
Y567564D03*
Y569138D03*
G54D51*
X432917Y968982D03*
X1409059Y968981D03*
G54D60*
X630328Y1640413D03*
Y1647027D03*
X916763Y981782D03*
Y975168D03*
X1175454Y1671059D03*
Y1677673D03*
X1661035Y1676874D03*
Y1683488D03*
G54D33*
X186530Y1521653D03*
X185720Y1518770D03*
Y1516670D03*
X186530Y1523753D03*
X177559Y1528907D03*
Y1531007D03*
X200703Y1521653D03*
X191254D03*
X195979D03*
X201254Y1528653D03*
Y1526553D03*
X200703Y1523753D03*
X191805Y1528653D03*
Y1526553D03*
X196530Y1528653D03*
Y1526553D03*
X191254Y1523753D03*
X195979D03*
X187081Y1528653D03*
Y1526553D03*
X194096Y1607286D03*
Y1609386D03*
X197696Y1607286D03*
Y1609386D03*
X214876Y1521653D03*
X210152D03*
X205427D03*
X214876Y1523753D03*
X210152D03*
X205978Y1528653D03*
Y1526553D03*
X210703Y1528653D03*
Y1526553D03*
X205427Y1523753D03*
X215427Y1528653D03*
Y1526553D03*
X206156Y1607286D03*
Y1609386D03*
X209756Y1607286D03*
Y1609386D03*
X229049Y1521653D03*
X224325D03*
X219601D03*
X229049Y1523753D03*
X224876Y1528653D03*
Y1526553D03*
X224325Y1523753D03*
X219601D03*
X229600Y1528653D03*
Y1526553D03*
X220152Y1528653D03*
Y1526553D03*
X230276Y1607286D03*
Y1609386D03*
X218216Y1607286D03*
Y1609386D03*
X221816Y1607286D03*
Y1609386D03*
X243223Y1521653D03*
X233774D03*
X238498D03*
X234325Y1528653D03*
Y1526553D03*
X243223Y1523753D03*
X233774D03*
X238498D03*
X239049Y1528653D03*
Y1526553D03*
X243774Y1528653D03*
Y1526553D03*
X233824Y1537963D03*
Y1540063D03*
X242336Y1607286D03*
Y1609386D03*
X245936Y1607286D03*
Y1609386D03*
X233876Y1607286D03*
Y1609386D03*
X252672Y1521653D03*
X257396D03*
X247947D03*
X252672Y1523753D03*
X253223Y1528653D03*
Y1526553D03*
X257947Y1528653D03*
Y1526553D03*
X257396Y1523753D03*
X248498Y1528653D03*
Y1526553D03*
X247947Y1523753D03*
X254396Y1607286D03*
Y1609386D03*
X257996Y1607286D03*
Y1609386D03*
X262141Y1521653D03*
Y1523753D03*
X266456Y1607286D03*
Y1609386D03*
X270056Y1607286D03*
Y1609386D03*
X290576Y1607286D03*
Y1609386D03*
X282116Y1607286D03*
Y1609386D03*
X278516Y1607286D03*
Y1609386D03*
X305621Y1528907D03*
Y1531007D03*
X302636Y1607286D03*
Y1609386D03*
X294176Y1607286D03*
Y1609386D03*
X314592Y1521653D03*
X319316D03*
X313782Y1518770D03*
Y1516670D03*
X319867Y1528653D03*
Y1526553D03*
X314592Y1523753D03*
X319316D03*
X315143Y1528653D03*
Y1526553D03*
X318296Y1607286D03*
Y1609386D03*
X314696Y1607286D03*
Y1609386D03*
X306236Y1607286D03*
Y1609386D03*
X333489Y1521653D03*
X328765D03*
X324041D03*
X333489Y1523753D03*
X334040Y1528653D03*
Y1526553D03*
X324592Y1528653D03*
Y1526553D03*
X328765Y1523753D03*
X329316Y1528653D03*
Y1526553D03*
X324041Y1523753D03*
X326756Y1607286D03*
Y1609386D03*
X330356Y1607286D03*
Y1609386D03*
X342938Y1521653D03*
X347663D03*
X338214D03*
X348214Y1528653D03*
Y1526553D03*
X343489Y1528653D03*
Y1526553D03*
X342938Y1523753D03*
X347663D03*
X338214D03*
X338765Y1528653D03*
Y1526553D03*
X338816Y1607286D03*
Y1609386D03*
X342416Y1607286D03*
Y1609386D03*
X352387Y1521653D03*
X357111D03*
X361836D03*
X352387Y1523753D03*
X352938Y1528653D03*
Y1526553D03*
X357111Y1523753D03*
X361836D03*
X362387Y1528653D03*
Y1526553D03*
X357662Y1528653D03*
Y1526553D03*
X361886Y1537963D03*
Y1540063D03*
X362936Y1607286D03*
Y1609386D03*
X350876Y1607286D03*
Y1609386D03*
X354476Y1607286D03*
Y1609386D03*
X366560Y1521653D03*
X376009D03*
X371285D03*
X366560Y1523753D03*
X367111Y1528653D03*
Y1526553D03*
X376560Y1528653D03*
Y1526553D03*
X376009Y1523753D03*
X371285D03*
X371836Y1528653D03*
Y1526553D03*
X374996Y1607286D03*
Y1609386D03*
X378596Y1607286D03*
Y1609386D03*
X366536Y1607286D03*
Y1609386D03*
X385458Y1521653D03*
X380734D03*
X390203D03*
X385458Y1523753D03*
X386009Y1528653D03*
Y1526553D03*
X380734Y1523753D03*
X381285Y1528653D03*
Y1526553D03*
X390203Y1523753D03*
X450703Y1521653D03*
X449893Y1518770D03*
Y1516670D03*
X450703Y1523753D03*
X451254Y1528653D03*
Y1526553D03*
X442340Y1609914D03*
Y1607814D03*
X445570Y1609784D03*
Y1607684D03*
X469600Y1521653D03*
X460152D03*
X455427D03*
X464876D03*
X469600Y1523753D03*
X460152D03*
X465427Y1528653D03*
Y1526553D03*
X460703Y1528653D03*
Y1526553D03*
X455427Y1523753D03*
X455978Y1528653D03*
Y1526553D03*
X464876Y1523753D03*
X461869Y1607286D03*
Y1609386D03*
X458269Y1607286D03*
Y1609386D03*
X483774Y1521653D03*
X479049D03*
X474325D03*
X479600Y1528653D03*
Y1526553D03*
X484325Y1528653D03*
Y1526553D03*
X483774Y1523753D03*
X479049D03*
X470151Y1528653D03*
Y1526553D03*
X474325Y1523753D03*
X474876Y1528653D03*
Y1526553D03*
X482389Y1607286D03*
Y1609386D03*
X470329Y1607286D03*
Y1609386D03*
X473929Y1607286D03*
Y1609386D03*
X488498Y1521653D03*
X493222D03*
X497947D03*
X488498Y1523753D03*
X489049Y1528653D03*
Y1526553D03*
X493222Y1523753D03*
X493773Y1528653D03*
Y1526553D03*
X497947Y1523753D03*
X498498Y1528653D03*
Y1526553D03*
X497997Y1537963D03*
Y1540063D03*
X494449Y1607286D03*
Y1609386D03*
X498049Y1607286D03*
Y1609386D03*
X485989Y1607286D03*
Y1609386D03*
X502671Y1521653D03*
X512120D03*
X507396D03*
X502671Y1523753D03*
X503222Y1528653D03*
Y1526553D03*
X507947Y1528653D03*
Y1526553D03*
X512120Y1523753D03*
X507396D03*
X512671Y1528653D03*
Y1526553D03*
X506509Y1607286D03*
Y1609386D03*
X510109Y1607286D03*
Y1609386D03*
X516845Y1521653D03*
X521569D03*
X526314D03*
X516845Y1523753D03*
X521569D03*
X526314D03*
X517396Y1528653D03*
Y1526553D03*
X522120Y1528653D03*
Y1526553D03*
X518569Y1607286D03*
Y1609386D03*
X522169Y1607286D03*
Y1609386D03*
X542689Y1607286D03*
Y1609386D03*
X530629Y1607286D03*
Y1609386D03*
X534229Y1607286D03*
Y1609386D03*
X554749Y1607286D03*
Y1609386D03*
X558349Y1607286D03*
Y1609386D03*
X546289Y1607286D03*
Y1609386D03*
X569794Y1528907D03*
Y1531007D03*
X566809Y1607286D03*
Y1609386D03*
X570409Y1607286D03*
Y1609386D03*
X577955Y1518770D03*
Y1516670D03*
X578765Y1521653D03*
X588214D03*
X583489D03*
X578765Y1523753D03*
X588765Y1528653D03*
Y1526553D03*
X588214Y1523753D03*
X579316Y1528653D03*
Y1526553D03*
X584040Y1528653D03*
Y1526553D03*
X583489Y1523753D03*
X578869Y1607286D03*
Y1609386D03*
X582469Y1607286D03*
Y1609386D03*
X597662Y1521653D03*
X592938D03*
X602387D03*
X597662Y1523753D03*
X598213Y1528653D03*
Y1526553D03*
X592938Y1523753D03*
X593489Y1528653D03*
Y1526553D03*
X602938Y1528653D03*
Y1526553D03*
X602387Y1523753D03*
X602989Y1607286D03*
Y1609386D03*
X590929Y1607286D03*
Y1609386D03*
X594529Y1607286D03*
Y1609386D03*
X611836Y1521653D03*
X616560D03*
X607111D03*
X607662Y1528653D03*
Y1526553D03*
X612387Y1528653D03*
Y1526553D03*
X611836Y1523753D03*
X617111Y1528653D03*
Y1526553D03*
X616560Y1523753D03*
X607111D03*
X615049Y1607286D03*
Y1609386D03*
X618649Y1607286D03*
Y1609386D03*
X606589Y1607286D03*
Y1609386D03*
X630733Y1521653D03*
X621284D03*
X626009D03*
X630733Y1523753D03*
X631284Y1528653D03*
Y1526553D03*
X621284Y1523753D03*
X621835Y1528653D03*
Y1526553D03*
X626560Y1528653D03*
Y1526553D03*
X626009Y1523753D03*
X626059Y1537963D03*
Y1540063D03*
X627109Y1607286D03*
Y1609386D03*
X630709Y1607286D03*
Y1609386D03*
X644907Y1521653D03*
X635458D03*
X640182D03*
X640733Y1528653D03*
Y1526553D03*
X644907Y1523753D03*
X635458D03*
X640182D03*
X636009Y1528653D03*
Y1526553D03*
X645458Y1528653D03*
Y1526553D03*
X639169Y1607286D03*
Y1609386D03*
X642769Y1607286D03*
Y1609386D03*
X643400Y1623840D03*
Y1621740D03*
X643580Y1629150D03*
Y1627050D03*
X646092Y1655321D03*
Y1653221D03*
X643800Y1670605D03*
X647000D03*
X640600D03*
X647500Y1677750D03*
Y1679850D03*
X643800Y1672705D03*
X647000D03*
X640600D03*
X649631Y1521653D03*
X654376D03*
X649960Y1514040D03*
Y1511940D03*
X649631Y1523753D03*
X654376D03*
X650182Y1528653D03*
Y1526553D03*
X649216Y1655321D03*
Y1653221D03*
X655406Y1671476D03*
X650200Y1670605D03*
X662600Y1657524D03*
Y1659624D03*
X655406Y1673576D03*
X650200Y1672705D03*
X666200Y1657524D03*
Y1659624D03*
X670962Y1667450D03*
Y1669550D03*
X670830Y1672389D03*
Y1674489D03*
X850500Y1313450D03*
Y1320550D03*
Y1318450D03*
X854000Y1322450D03*
Y1324550D03*
Y1327450D03*
X850500Y1315550D03*
X854000Y1329550D03*
X850500Y1331450D03*
Y1333550D03*
Y1338550D03*
Y1336450D03*
X854000Y1340450D03*
Y1342550D03*
Y1347550D03*
Y1345450D03*
X915500Y1313450D03*
X912000Y1322450D03*
Y1324550D03*
Y1327450D03*
X915500Y1320550D03*
Y1318450D03*
Y1315550D03*
X912000Y1340450D03*
Y1342550D03*
X915500Y1338550D03*
Y1336450D03*
Y1331450D03*
Y1333550D03*
X912000Y1329550D03*
Y1347550D03*
Y1345450D03*
X1185432Y1561907D03*
Y1564007D03*
X1185363Y1684784D03*
Y1682684D03*
X1193593Y1551770D03*
Y1549670D03*
X1199127Y1554653D03*
Y1556753D03*
X1194403Y1554653D03*
Y1556753D03*
X1199678Y1561653D03*
Y1559553D03*
X1194954Y1561653D03*
Y1559553D03*
X1187147Y1670012D03*
Y1672112D03*
X1213851Y1561653D03*
Y1559553D03*
X1213300Y1554653D03*
Y1556753D03*
X1209127Y1561653D03*
Y1559553D03*
X1203852Y1554653D03*
Y1556753D03*
X1208576Y1554653D03*
Y1556753D03*
X1204403Y1561653D03*
Y1559553D03*
X1214029Y1640286D03*
X1205569D03*
X1201969D03*
X1214029Y1642386D03*
X1205569D03*
X1201969D03*
X1223300Y1561653D03*
Y1559553D03*
X1228025Y1561653D03*
Y1559553D03*
X1227474Y1554653D03*
Y1556753D03*
X1222749Y1554653D03*
Y1556753D03*
X1218576Y1561653D03*
Y1559553D03*
X1218025Y1554653D03*
Y1556753D03*
X1229689Y1640286D03*
X1226089D03*
X1217629D03*
X1229689Y1642386D03*
X1226089D03*
X1217629D03*
X1232198Y1554653D03*
Y1556753D03*
X1232749Y1561653D03*
Y1559553D03*
X1236922Y1554653D03*
Y1556753D03*
X1241647Y1554653D03*
Y1556753D03*
X1242198Y1561653D03*
Y1559553D03*
X1237473Y1561653D03*
Y1559553D03*
X1241697Y1570963D03*
Y1573063D03*
X1241749Y1640286D03*
X1238149D03*
X1241749Y1642386D03*
X1238149D03*
X1246922Y1561653D03*
Y1559553D03*
X1246371Y1554653D03*
Y1556753D03*
X1251096Y1554653D03*
Y1556753D03*
X1255820Y1554653D03*
Y1556753D03*
X1251647Y1561653D03*
Y1559553D03*
X1256371Y1561653D03*
Y1559553D03*
X1253809Y1640286D03*
X1250209D03*
X1253809Y1642386D03*
X1250209D03*
X1265269Y1554653D03*
Y1556753D03*
X1261096Y1561653D03*
Y1559553D03*
X1260545Y1554653D03*
Y1556753D03*
X1270014Y1554653D03*
Y1556753D03*
X1265820Y1561653D03*
Y1559553D03*
X1274329Y1640286D03*
X1265869D03*
X1262269D03*
X1274329Y1642386D03*
X1265869D03*
X1262269D03*
X1286389Y1640286D03*
X1277929D03*
X1286389Y1642386D03*
X1277929D03*
X1302049Y1640286D03*
X1298449D03*
X1289989D03*
X1302049Y1642386D03*
X1298449D03*
X1289989D03*
X1313494Y1561907D03*
Y1564007D03*
X1314109Y1640286D03*
X1310509D03*
X1314109Y1642386D03*
X1310509D03*
X1321655Y1551770D03*
Y1549670D03*
X1332465Y1561653D03*
Y1559553D03*
X1327189Y1554653D03*
Y1556753D03*
X1331914Y1554653D03*
Y1556753D03*
X1322465Y1554653D03*
Y1556753D03*
X1323016Y1561653D03*
Y1559553D03*
X1327740Y1561653D03*
Y1559553D03*
X1334629Y1640286D03*
X1326169D03*
X1322569D03*
X1334629Y1642386D03*
X1326169D03*
X1322569D03*
X1341913Y1561653D03*
Y1559553D03*
X1341362Y1554653D03*
Y1556753D03*
X1336638Y1554653D03*
Y1556753D03*
X1337189Y1561653D03*
Y1559553D03*
X1346638Y1561653D03*
Y1559553D03*
X1346087Y1554653D03*
Y1556753D03*
X1346689Y1640286D03*
X1338229D03*
X1346689Y1642386D03*
X1338229D03*
X1351362Y1561653D03*
Y1559553D03*
X1356087Y1561653D03*
Y1559553D03*
X1350811Y1554653D03*
Y1556753D03*
X1360260Y1554653D03*
Y1556753D03*
X1355536Y1554653D03*
Y1556753D03*
X1360811Y1561653D03*
Y1559553D03*
X1362349Y1640286D03*
X1358749D03*
X1350289D03*
X1362349Y1642386D03*
X1358749D03*
X1350289D03*
X1374984Y1561653D03*
Y1559553D03*
X1374433Y1554653D03*
Y1556753D03*
X1364984Y1554653D03*
Y1556753D03*
X1379158Y1554653D03*
Y1556753D03*
X1365535Y1561653D03*
Y1559553D03*
X1370260Y1561653D03*
Y1559553D03*
X1369709Y1554653D03*
Y1556753D03*
X1369759Y1570963D03*
Y1573063D03*
X1374409Y1640286D03*
X1370809D03*
X1374409Y1642386D03*
X1370809D03*
X1383882Y1554653D03*
Y1556753D03*
X1379709Y1561653D03*
Y1559553D03*
X1389158Y1561653D03*
Y1559553D03*
X1388607Y1554653D03*
Y1556753D03*
X1393331Y1554653D03*
Y1556753D03*
X1384433Y1561653D03*
Y1559553D03*
X1393882Y1561653D03*
Y1559553D03*
X1386469Y1640286D03*
X1382869D03*
X1386469Y1642386D03*
X1382869D03*
X1398076Y1554653D03*
Y1556753D03*
X1449606Y1561907D03*
Y1564007D03*
X1450980Y1677333D03*
Y1675233D03*
X1457767Y1551770D03*
Y1549670D03*
X1468026Y1554653D03*
Y1556753D03*
X1458577Y1554653D03*
Y1556753D03*
X1463301Y1554653D03*
Y1556753D03*
X1463852Y1561653D03*
Y1559553D03*
X1468577Y1561653D03*
Y1559553D03*
X1459128Y1561653D03*
Y1559553D03*
X1466143Y1640286D03*
Y1642386D03*
X1477474Y1554653D03*
Y1556753D03*
X1478025Y1561653D03*
Y1559553D03*
X1472750Y1554653D03*
Y1556753D03*
X1473301Y1561653D03*
Y1559553D03*
X1482199Y1554653D03*
Y1556753D03*
X1482750Y1561653D03*
Y1559553D03*
X1481803Y1640286D03*
X1478203D03*
X1469743D03*
X1481803Y1642386D03*
X1478203D03*
X1469743D03*
X1492199Y1561653D03*
Y1559553D03*
X1487474Y1561653D03*
Y1559553D03*
X1486923Y1554653D03*
Y1556753D03*
X1496372Y1554653D03*
Y1556753D03*
X1491648Y1554653D03*
Y1556753D03*
X1496923Y1561653D03*
Y1559553D03*
X1493863Y1640286D03*
X1490263D03*
X1493863Y1642386D03*
X1490263D03*
X1511096Y1561653D03*
Y1559553D03*
X1510545Y1554653D03*
Y1556753D03*
X1501096Y1554653D03*
Y1556753D03*
X1501647Y1561653D03*
Y1559553D03*
X1505821Y1554653D03*
Y1556753D03*
X1506372Y1561653D03*
Y1559553D03*
X1505871Y1570963D03*
Y1573063D03*
X1505923Y1640286D03*
X1502323D03*
X1505923Y1642386D03*
X1502323D03*
X1524719Y1554653D03*
Y1556753D03*
X1525270Y1561653D03*
Y1559553D03*
X1519994Y1554653D03*
Y1556753D03*
X1515270Y1554653D03*
Y1556753D03*
X1520545Y1561653D03*
Y1559553D03*
X1515821Y1561653D03*
Y1559553D03*
X1526443Y1640286D03*
X1517983D03*
X1514383D03*
X1526443Y1642386D03*
X1517983D03*
X1514383D03*
X1529994Y1561653D03*
Y1559553D03*
X1529443Y1554653D03*
Y1556753D03*
X1534188Y1554653D03*
Y1556753D03*
X1542103Y1640286D03*
X1538503D03*
X1530043D03*
X1542103Y1642386D03*
X1538503D03*
X1530043D03*
X1554163Y1640286D03*
X1550563D03*
X1554163Y1642386D03*
X1550563D03*
X1566223Y1640286D03*
X1562623D03*
X1566223Y1642386D03*
X1562623D03*
X1585829Y1551770D03*
Y1549670D03*
X1577668Y1561907D03*
Y1564007D03*
X1587190Y1561653D03*
Y1559553D03*
X1586639Y1554653D03*
Y1556753D03*
X1586743Y1640286D03*
X1578283D03*
X1574683D03*
X1586743Y1642386D03*
X1578283D03*
X1574683D03*
X1600812Y1554653D03*
Y1556753D03*
X1591363Y1554653D03*
Y1556753D03*
X1591914Y1561653D03*
Y1559553D03*
X1596639Y1561653D03*
Y1559553D03*
X1596088Y1554653D03*
Y1556753D03*
X1601363Y1561653D03*
Y1559553D03*
X1602403Y1640286D03*
X1598803D03*
X1590343D03*
X1602403Y1642386D03*
X1598803D03*
X1590343D03*
X1615536Y1561653D03*
Y1559553D03*
X1614985Y1554653D03*
Y1556753D03*
X1605536Y1554653D03*
Y1556753D03*
X1606087Y1561653D03*
Y1559553D03*
X1610261Y1554653D03*
Y1556753D03*
X1610812Y1561653D03*
Y1559553D03*
X1614463Y1640286D03*
X1610863D03*
X1614463Y1642386D03*
X1610863D03*
X1629709Y1561653D03*
Y1559553D03*
X1620261Y1561653D03*
Y1559553D03*
X1619710Y1554653D03*
Y1556753D03*
X1624985Y1561653D03*
Y1559553D03*
X1624434Y1554653D03*
Y1556753D03*
X1629158Y1554653D03*
Y1556753D03*
X1626523Y1640286D03*
X1622923D03*
X1626523Y1642386D03*
X1622923D03*
X1638607Y1554653D03*
Y1556753D03*
X1639158Y1561653D03*
Y1559553D03*
X1643883Y1561653D03*
Y1559553D03*
X1643332Y1554653D03*
Y1556753D03*
X1634434Y1561653D03*
Y1559553D03*
X1633883Y1554653D03*
Y1556753D03*
X1633933Y1570963D03*
Y1573063D03*
X1647043Y1640286D03*
X1638583D03*
X1634983D03*
X1647043Y1642386D03*
X1638583D03*
X1634983D03*
X1657836Y1547053D03*
Y1544953D03*
X1657505Y1554653D03*
Y1556753D03*
X1658056Y1561653D03*
Y1559553D03*
X1648607Y1561653D03*
Y1559553D03*
X1652781Y1554653D03*
Y1556753D03*
X1662250Y1554653D03*
Y1556753D03*
X1648056Y1554653D03*
Y1556753D03*
X1653332Y1561653D03*
Y1559553D03*
X1650643Y1640286D03*
Y1642386D03*
X1671986Y1678943D03*
Y1681043D03*
X1671906Y1686556D03*
Y1684456D03*
G54D15*
X33000Y318016D03*
X43500D03*
X38733Y1610612D03*
X48167Y1629921D03*
X65397Y381644D03*
X57544Y397012D03*
X53738Y396986D03*
X56722Y435542D03*
X60761Y435475D03*
X60822Y521311D03*
X53742Y531781D03*
X60772Y531931D03*
X59503Y755848D03*
X69998Y381753D03*
X81667Y1608921D03*
X77667D03*
X99000Y1444016D03*
X186579Y1536154D03*
X182813Y1662012D03*
X182517Y1692079D03*
X196029Y1536154D03*
X200753D03*
X191304D03*
X210202D03*
X214926D03*
X205478D03*
X203660Y1668694D03*
X203807Y1683811D03*
X207660Y1675694D03*
X203807Y1698929D03*
X207807Y1690811D03*
X203807Y1705929D03*
X219651Y1536154D03*
X224375D03*
X229100D03*
X242220Y33878D03*
X246220D03*
X241787Y59856D03*
X234827Y696589D03*
X238548Y1536154D03*
X243273D03*
X254122Y33886D03*
X250220Y33878D03*
X246805Y59856D03*
X252722Y1536154D03*
X257446D03*
X247997D03*
X272870Y653096D03*
X267553Y659419D03*
X269871Y792004D03*
X262777Y1536154D03*
X290716Y42881D03*
X286716D03*
X293520Y15253D03*
X303720Y42878D03*
X300020D03*
X305600Y687337D03*
X300283Y693660D03*
X314641Y1536154D03*
X319366D03*
X333053Y713810D03*
X324091Y1536154D03*
X328815D03*
X333540D03*
X338370Y707487D03*
X342988Y1536154D03*
X338264D03*
X347713D03*
X362073Y594487D03*
X363313Y806191D03*
X359813D03*
X356313D03*
X352813D03*
X363313Y814991D03*
X359813Y815091D03*
X356313D03*
X352813D03*
X361271Y1213504D03*
X357271D03*
X352437Y1536154D03*
X357162D03*
X371430Y707219D03*
X366113Y713542D03*
X366813Y806191D03*
X377313D03*
X373813D03*
X370313D03*
X366610Y1536154D03*
X371335D03*
X376059D03*
X395657Y549431D03*
X387657D03*
X391657D03*
X394271Y1069004D03*
X385508Y1536154D03*
X380784D03*
X390839D03*
X399657Y549431D03*
X403657D03*
X404470Y707287D03*
X399153Y713610D03*
X408500Y1646516D03*
X424874Y104628D03*
X420874D03*
X420748Y121876D03*
X423926Y1029020D03*
X420831Y1620675D03*
X416123Y1620696D03*
X411636Y1623840D03*
X412000Y1636016D03*
X432874Y104628D03*
X428874D03*
X436874D03*
X434990Y136658D03*
X431090D03*
X427190D03*
X438890D03*
X433710Y242681D03*
X437470Y689487D03*
X432153Y695810D03*
X440159Y967282D03*
Y974782D03*
Y982282D03*
X427666Y1029020D03*
X438886D03*
X431406D03*
X435146D03*
X428000Y1643516D03*
X440874Y104628D03*
X442790Y136658D03*
X442626Y1029020D03*
X450107D03*
X453847D03*
X446366D03*
X450752Y1536154D03*
X459457Y100980D03*
X455457D03*
X469870Y664887D03*
X464553Y671210D03*
X457587Y1029020D03*
X460202Y1536154D03*
X464926D03*
X469651D03*
X455477D03*
X457151Y1635958D03*
X457000Y1644016D03*
X476639Y312443D03*
X479099Y1536154D03*
X474375D03*
X483824D03*
X495652Y151561D03*
X499652D03*
X497153Y644710D03*
X488071Y1068804D03*
X488548Y1536154D03*
X493273D03*
X513618Y159964D03*
X502470Y638387D03*
X502721Y1536154D03*
X507446D03*
X512170D03*
X517618Y159964D03*
X525618D03*
X521618D03*
X518075Y837898D03*
X516895Y1536154D03*
X521619D03*
X526950D03*
X538968Y250651D03*
X535770Y604287D03*
X530453Y610610D03*
X544651Y647954D03*
X546350Y34101D03*
X548380Y130509D03*
X558968Y250651D03*
X564200Y52698D03*
X572200D03*
X568200Y52709D03*
X560200Y52704D03*
X567333Y66678D03*
X572171Y800404D03*
X576200Y52738D03*
X588968Y250651D03*
X587571Y800504D03*
X575671Y800404D03*
X578814Y1536154D03*
X588264D03*
X583539D03*
X602350Y52698D03*
X594405D03*
X590097D03*
X603771Y782904D03*
X591571Y793704D03*
X603261Y797456D03*
X602201Y1234591D03*
X597971Y1244004D03*
X602437Y1536154D03*
X592988D03*
X597713D03*
X614845Y52698D03*
X610285D03*
X606330D03*
X615571Y782904D03*
X606201Y1234591D03*
X612171Y1242804D03*
X607161Y1536154D03*
X616610D03*
X611886D03*
X627496Y77477D03*
X630783Y1536154D03*
X621335D03*
X647672Y34002D03*
X634220Y58981D03*
X645222Y52276D03*
X640670Y77477D03*
X646719Y427953D03*
X644957Y1536154D03*
X635508D03*
X640232D03*
X643258Y1700786D03*
Y1693786D03*
Y1714786D03*
X647258Y1707786D03*
X651910Y34002D03*
X649222Y52276D03*
X659045Y414877D03*
X658603Y1367020D03*
X649681Y1536154D03*
X655012D03*
X675500Y384878D03*
X668058Y1714468D03*
X690291Y54848D03*
X683500Y384878D03*
X679500D03*
X702481Y52674D03*
X698597Y52698D03*
X694400D03*
X707849Y127209D03*
X708652Y497860D03*
X700652D03*
X704652D03*
X705815Y1657472D03*
X709303Y53227D03*
X720010Y78745D03*
X716033D03*
X712043D03*
X719438Y380850D03*
X715500Y393378D03*
X711500D03*
X719500D03*
X708800Y418636D03*
X712652Y497860D03*
X720652D03*
X711344Y522348D03*
X718381Y525457D03*
X718500Y571516D03*
X714090Y1600559D03*
X717694Y1601744D03*
X713317Y1624302D03*
X709317Y1634802D03*
X709771Y1657481D03*
X717749Y1657475D03*
X722630Y1663914D03*
X724000Y78745D03*
X727500Y393378D03*
X724652Y497860D03*
X733160Y522957D03*
X733191Y516455D03*
X729624Y524410D03*
X725424Y525254D03*
X726302Y1660754D03*
X730302D03*
X747500Y393378D03*
X742956Y536540D03*
X748482Y551526D03*
X753010Y1576114D03*
Y1584114D03*
X763500Y380878D03*
X767500D03*
X759500Y393378D03*
X763500D03*
X760517Y551400D03*
X785500Y536516D03*
X791500Y541516D03*
X785000Y566516D03*
X789000D03*
X808220Y140078D03*
X821120Y139478D03*
X837500Y223168D03*
X841720Y212878D03*
X858528Y264898D03*
X899707Y1136574D03*
X915500Y857016D03*
X905500D03*
X910500D03*
X903843Y896718D03*
X909000Y912516D03*
X913000D03*
X905000D03*
X925500Y920016D03*
X918780Y1663278D03*
X931798D03*
X923798D03*
X927798D03*
X934000Y861016D03*
X943000Y855516D03*
X938000D03*
X946500Y920016D03*
X938500D03*
X946732Y1136574D03*
X939798Y1663278D03*
X935798D03*
X949500Y880516D03*
X954500Y920016D03*
X948500Y931016D03*
X961023Y1506139D03*
X947798Y1663278D03*
X951798D03*
X984555Y177499D03*
X1016567Y207644D03*
X1123228Y1653439D03*
X1118402Y1653994D03*
X1134649Y1653561D03*
X1194452Y1569154D03*
X1199177D03*
X1214094Y261149D03*
X1203902Y1569154D03*
X1208626D03*
X1213351D03*
X1230094Y261149D03*
X1222094D03*
Y308657D03*
X1222799Y1569154D03*
X1218075D03*
X1227524D03*
X1238094Y261149D03*
X1240177Y793504D03*
X1235177D03*
X1232248Y1569154D03*
X1236973D03*
X1254094Y261149D03*
X1246094D03*
X1247785Y300248D03*
X1251146Y1569154D03*
X1246421D03*
X1255870D03*
X1262094Y261149D03*
X1270094D03*
X1269177Y801340D03*
X1260677D03*
X1260595Y1569154D03*
X1265319D03*
X1270650D03*
X1286094Y261149D03*
X1278094D03*
X1282677Y794240D03*
X1286677D03*
X1282677Y801340D03*
X1294094Y261149D03*
X1302094D03*
X1318094D03*
X1310094D03*
X1307824Y593527D03*
X1326094Y261149D03*
X1334094D03*
X1332877Y844504D03*
X1333977Y1215894D03*
X1322514Y1569154D03*
X1331964D03*
X1327239D03*
X1342094Y261149D03*
X1346717Y666404D03*
X1336877Y844504D03*
X1346137Y1569154D03*
X1336688D03*
X1341413D03*
X1358094Y261149D03*
X1350094D03*
X1350861Y1569154D03*
X1360310D03*
X1355586D03*
X1366094Y261149D03*
X1378105Y628753D03*
X1370477Y1068904D03*
X1374483Y1569154D03*
X1379208D03*
X1365035D03*
X1383422Y622430D03*
X1393381Y1569154D03*
X1388657D03*
X1383932D03*
X1400068Y1029019D03*
X1403808D03*
X1407548D03*
X1398712Y1569154D03*
X1396901Y1654524D03*
X1416122Y655330D03*
X1410805Y661653D03*
X1416301Y967281D03*
Y974781D03*
Y982281D03*
X1422508Y1029019D03*
X1418768D03*
X1411288D03*
X1415028D03*
X1433729D03*
X1426249D03*
X1429989D03*
X1448722Y687910D03*
X1443405Y694233D03*
X1465832Y537918D03*
X1461159Y843098D03*
X1465559D03*
X1464177Y1068804D03*
X1468076Y1569154D03*
X1458626D03*
X1463351D03*
X1475473Y585349D03*
X1481640Y707487D03*
X1476323Y713810D03*
X1477177Y806004D03*
X1473177D03*
X1478177Y819504D03*
X1482177D03*
X1483159Y843098D03*
X1478759D03*
X1474359D03*
X1469959D03*
X1482249Y1569154D03*
X1472800D03*
X1477525D03*
X1489177Y806004D03*
X1498177Y819504D03*
X1494177D03*
X1487559Y843098D03*
X1491959D03*
X1496359D03*
X1486973Y1569154D03*
X1491698D03*
X1496422D03*
X1508757Y539993D03*
X1500757D03*
X1504757D03*
X1512757D03*
X1509405Y713810D03*
X1500759Y843098D03*
X1510595Y1569154D03*
X1501147D03*
X1516757Y539993D03*
X1514722Y707487D03*
X1515320Y1569154D03*
X1524769D03*
X1520044D03*
X1542205Y713810D03*
X1539782Y1235447D03*
X1529493Y1569154D03*
X1534824D03*
X1547522Y707487D03*
X1555603Y788924D03*
X1550432Y788842D03*
X1543772Y1235417D03*
X1567836Y570963D03*
X1559618Y788890D03*
X1569148Y1341714D03*
X1572924D03*
X1572906Y1356194D03*
X1580652Y685547D03*
X1575335Y691870D03*
X1579205Y1303085D03*
X1580924Y1341714D03*
Y1356194D03*
X1586688Y1569154D03*
X1592852Y1301074D03*
X1596138Y1569154D03*
X1600862D03*
X1591413D03*
X1609141Y595422D03*
X1613422Y651778D03*
X1608105Y658101D03*
X1608652Y1289329D03*
Y1297679D03*
X1610311Y1569154D03*
X1615035D03*
X1605587D03*
X1620379Y547451D03*
X1624484Y1569154D03*
X1619760D03*
X1629209D03*
X1646422Y632778D03*
X1641105Y639101D03*
X1643382Y1569154D03*
X1638657D03*
X1655147Y676824D03*
X1657555Y1569154D03*
X1652831D03*
X1648106D03*
X1662886D03*
X1690560Y427128D03*
X1680147Y1308074D03*
X1685383Y1716684D03*
Y1723684D03*
X1712799Y104368D03*
X1710230Y1723366D03*
X1750463Y1646481D03*
X1762062Y40119D03*
X1755463Y1646481D03*
X1773757Y31416D03*
X1777754Y40385D03*
X1773554Y40225D03*
X1769900D03*
X1781990Y40271D03*
X1787672Y50102D03*
X1791672D03*
X1807296Y257549D03*
G54D42*
X367996Y558596D03*
X369570D03*
X371145D03*
X372720D03*
X374295D03*
X375870D03*
X377444D03*
X379019D03*
Y581234D03*
X377444D03*
X375870D03*
X374295D03*
X372720D03*
X371145D03*
X369570D03*
X367996D03*
X380594Y558596D03*
X382169D03*
X383744D03*
X385318D03*
Y581234D03*
X383744D03*
X382169D03*
X380594D03*
X1481096Y549158D03*
X1482670D03*
Y571796D03*
X1481096D03*
X1484245Y549158D03*
X1485820D03*
X1487395D03*
X1488970D03*
X1490544D03*
X1492119D03*
X1493694D03*
X1495269D03*
X1496844D03*
Y571796D03*
X1495269D03*
X1493694D03*
X1492119D03*
X1490544D03*
X1488970D03*
X1487395D03*
X1485820D03*
X1484245D03*
X1498418Y549158D03*
Y571796D03*
G54D24*
X50696Y439840D03*
Y441415D03*
Y442989D03*
Y444564D03*
X44396D03*
Y442989D03*
Y441415D03*
Y439840D03*
G54D52*
X434513Y978703D03*
X1410419D03*
G54D43*
X376657Y569915D03*
X1489757Y560477D03*
G54D70*
X705366Y1669626D03*
X701626D03*
Y1679940D03*
X705366D03*
X709106Y1669626D03*
Y1679940D03*
G54D61*
X632848Y1640767D03*
X627808D03*
X632848Y1646673D03*
X627808D03*
X914243Y981428D03*
Y975522D03*
X919283D03*
Y981428D03*
X1172934Y1671413D03*
X1177974D03*
X1172934Y1677319D03*
X1177974D03*
X1658515Y1677228D03*
Y1683134D03*
X1663555Y1677228D03*
Y1683134D03*
G54D16*
X33000Y320983D03*
X43500D03*
X38733Y1613579D03*
X48167Y1632888D03*
X65397Y384611D03*
X57544Y399979D03*
X53738Y399953D03*
X56722Y438509D03*
X60761Y438442D03*
X60822Y524278D03*
X53742Y534748D03*
X60772Y534898D03*
X59503Y758815D03*
X69998Y384720D03*
X81667Y1611888D03*
X77667D03*
X99000Y1446983D03*
X186579Y1539121D03*
X182813Y1664979D03*
X182517Y1695046D03*
X196029Y1539121D03*
X200753D03*
X191304D03*
X210202D03*
X214926D03*
X205478D03*
X203660Y1671661D03*
X203807Y1686778D03*
X207660Y1678661D03*
X203807Y1701896D03*
X207807Y1693778D03*
X203807Y1708896D03*
X219651Y1539121D03*
X224375D03*
X229100D03*
X242220Y36845D03*
X246220D03*
X241787Y62823D03*
X234827Y699556D03*
X238548Y1539121D03*
X243273D03*
X254122Y36853D03*
X250220Y36845D03*
X246805Y62823D03*
X252722Y1539121D03*
X257446D03*
X247997D03*
X272870Y656063D03*
X267553Y662386D03*
X269871Y794971D03*
X262777Y1539121D03*
X290716Y45848D03*
X286716D03*
X293520Y18220D03*
X303720Y45845D03*
X300020D03*
X305600Y690304D03*
X300283Y696627D03*
X314641Y1539121D03*
X319366D03*
X333053Y716777D03*
X324091Y1539121D03*
X328815D03*
X333540D03*
X338370Y710454D03*
X342988Y1539121D03*
X338264D03*
X347713D03*
X362073Y597454D03*
X363313Y809158D03*
X359813D03*
X356313D03*
X363313Y817958D03*
X359813Y818058D03*
X356313D03*
X352813Y809158D03*
Y818058D03*
X361271Y1216471D03*
X357271D03*
X352437Y1539121D03*
X357162D03*
X371430Y710186D03*
X366113Y716509D03*
X366813Y809158D03*
X377313D03*
X373813D03*
X370313D03*
X366610Y1539121D03*
X371335D03*
X376059D03*
X395657Y552398D03*
X387657D03*
X391657D03*
X394271Y1071971D03*
X385508Y1539121D03*
X380784D03*
X390839D03*
X399657Y552398D03*
X403657D03*
X404470Y710254D03*
X399153Y716577D03*
X408500Y1649483D03*
X424874Y107595D03*
X420874D03*
X420748Y124843D03*
X423926Y1031987D03*
X420831Y1623642D03*
X416123Y1623663D03*
X411636Y1626807D03*
X412000Y1638983D03*
X432874Y107595D03*
X428874D03*
X436874D03*
X434990Y139625D03*
X431090D03*
X427190D03*
X438890D03*
X433710Y245648D03*
X437470Y692454D03*
X432153Y698777D03*
X440159Y970249D03*
Y977749D03*
Y985249D03*
X427666Y1031987D03*
X438886D03*
X431406D03*
X435146D03*
X428000Y1646483D03*
X440874Y107595D03*
X442790Y139625D03*
X442626Y1031987D03*
X450107D03*
X453847D03*
X446366D03*
X450752Y1539121D03*
X459457Y103947D03*
X455457D03*
X469870Y667854D03*
X464553Y674177D03*
X457587Y1031987D03*
X460202Y1539121D03*
X464926D03*
X469651D03*
X455477D03*
X457151Y1638925D03*
X457000Y1646983D03*
X476639Y315410D03*
X479099Y1539121D03*
X474375D03*
X483824D03*
X495652Y154528D03*
X499652D03*
X497153Y647677D03*
X488071Y1071771D03*
X488548Y1539121D03*
X493273D03*
X513618Y162931D03*
X502470Y641354D03*
X502721Y1539121D03*
X507446D03*
X512170D03*
X517618Y162931D03*
X525618D03*
X521618D03*
X518075Y840865D03*
X516895Y1539121D03*
X521619D03*
X526950D03*
X538968Y253618D03*
X535770Y607254D03*
X530453Y613577D03*
X544651Y650921D03*
X546350Y37068D03*
X548380Y133476D03*
X558968Y253618D03*
X564200Y55665D03*
X572200D03*
X568200Y55676D03*
X560200Y55671D03*
X567333Y69645D03*
X572171Y803371D03*
X576200Y55705D03*
X588968Y253618D03*
X587571Y803471D03*
X575671Y803371D03*
X578814Y1539121D03*
X588264D03*
X583539D03*
X602350Y55665D03*
X594405D03*
X590097D03*
X603771Y785871D03*
X591571Y796671D03*
X603261Y800423D03*
X602201Y1237558D03*
X597971Y1246971D03*
X602437Y1539121D03*
X592988D03*
X597713D03*
X614845Y55665D03*
X610285D03*
X606330D03*
X615571Y785871D03*
X606201Y1237558D03*
X612171Y1245771D03*
X607161Y1539121D03*
X616610D03*
X611886D03*
X627496Y80444D03*
X630783Y1539121D03*
X621335D03*
X647672Y36969D03*
X634220Y61948D03*
X645222Y55243D03*
X640670Y80444D03*
X646719Y430920D03*
X644957Y1539121D03*
X635508D03*
X640232D03*
X643258Y1696753D03*
X647258Y1710753D03*
X643258Y1703753D03*
Y1717753D03*
X651910Y36969D03*
X649222Y55243D03*
X659045Y417844D03*
X658603Y1369987D03*
X649681Y1539121D03*
X655012D03*
X675500Y387845D03*
X668058Y1717435D03*
X690291Y57815D03*
X683500Y387845D03*
X679500D03*
X702481Y55641D03*
X698597Y55665D03*
X694400D03*
X707849Y130176D03*
X708652Y500827D03*
X700652D03*
X704652D03*
X705815Y1660439D03*
X709303Y56194D03*
X720010Y81712D03*
X716033D03*
X712043D03*
X719438Y383817D03*
X715500Y396345D03*
X711500D03*
X719500D03*
X708800Y421603D03*
X712652Y500827D03*
X720652D03*
X711344Y525315D03*
X718381Y528424D03*
X718500Y574483D03*
X714090Y1603526D03*
X717694Y1604711D03*
X713317Y1627269D03*
X709317Y1637769D03*
X709771Y1660448D03*
X717749Y1660442D03*
X722630Y1666881D03*
X724000Y81712D03*
X727500Y396345D03*
X724652Y500827D03*
X733191Y519422D03*
X729624Y527377D03*
X725424Y528221D03*
X733160Y525924D03*
X726302Y1663721D03*
X730302D03*
X747500Y396345D03*
X742956Y539507D03*
X748482Y554493D03*
X753010Y1579081D03*
Y1587081D03*
X763500Y383845D03*
X767500D03*
X759500Y396345D03*
X763500D03*
X760517Y554367D03*
X791500Y544483D03*
X785500Y539483D03*
X785000Y569483D03*
X789000D03*
X808220Y143045D03*
X821120Y142445D03*
X841720Y215845D03*
X837500Y226135D03*
X858528Y267865D03*
X899707Y1139541D03*
X915500Y859983D03*
X905500D03*
X910500D03*
X903843Y899685D03*
X909000Y915483D03*
X913000D03*
X905000D03*
X925500Y922983D03*
X918780Y1666245D03*
X931798D03*
X923798D03*
X927798D03*
X934000Y863983D03*
X943000Y858483D03*
X938000D03*
X946500Y922983D03*
X938500D03*
X946732Y1139541D03*
X939798Y1666245D03*
X935798D03*
X949500Y883483D03*
X954500Y922983D03*
X948500Y933983D03*
X961023Y1509106D03*
X947798Y1666245D03*
X951798D03*
X984555Y180466D03*
X1016567Y210611D03*
X1123228Y1656406D03*
X1118402Y1656961D03*
X1134649Y1656528D03*
X1194452Y1572121D03*
X1199177D03*
X1214094Y264116D03*
X1203902Y1572121D03*
X1208626D03*
X1213351D03*
X1230094Y264116D03*
X1222094D03*
Y311624D03*
X1222799Y1572121D03*
X1218075D03*
X1227524D03*
X1238094Y264116D03*
X1240177Y796471D03*
X1235177D03*
X1232248Y1572121D03*
X1236973D03*
X1254094Y264116D03*
X1246094D03*
X1247785Y303215D03*
X1251146Y1572121D03*
X1246421D03*
X1255870D03*
X1262094Y264116D03*
X1270094D03*
X1269177Y804307D03*
X1260677D03*
X1260595Y1572121D03*
X1265319D03*
X1270650D03*
X1286094Y264116D03*
X1278094D03*
X1282677Y797207D03*
X1286677D03*
X1282677Y804307D03*
X1294094Y264116D03*
X1302094D03*
X1318094D03*
X1310094D03*
X1307824Y596494D03*
X1326094Y264116D03*
X1334094D03*
X1332877Y847471D03*
X1333977Y1218861D03*
X1322514Y1572121D03*
X1331964D03*
X1327239D03*
X1342094Y264116D03*
X1346717Y669371D03*
X1336877Y847471D03*
X1346137Y1572121D03*
X1336688D03*
X1341413D03*
X1358094Y264116D03*
X1350094D03*
X1350861Y1572121D03*
X1360310D03*
X1355586D03*
X1366094Y264116D03*
X1378105Y631720D03*
X1370477Y1071871D03*
X1374483Y1572121D03*
X1379208D03*
X1365035D03*
X1383422Y625397D03*
X1393381Y1572121D03*
X1388657D03*
X1383932D03*
X1400068Y1031986D03*
X1403808D03*
X1407548D03*
X1398712Y1572121D03*
X1396901Y1657491D03*
X1416122Y658297D03*
X1410805Y664620D03*
X1416301Y970248D03*
Y977748D03*
Y985248D03*
X1422508Y1031986D03*
X1418768D03*
X1411288D03*
X1415028D03*
X1433729D03*
X1426249D03*
X1429989D03*
X1448722Y690877D03*
X1443405Y697200D03*
X1465832Y540885D03*
X1461159Y846065D03*
X1465559D03*
X1464177Y1071771D03*
X1468076Y1572121D03*
X1458626D03*
X1463351D03*
X1475473Y588316D03*
X1481640Y710454D03*
X1476323Y716777D03*
X1477177Y808971D03*
X1473177D03*
X1478177Y822471D03*
X1482177D03*
X1483159Y846065D03*
X1478759D03*
X1474359D03*
X1469959D03*
X1482249Y1572121D03*
X1472800D03*
X1477525D03*
X1489177Y808971D03*
X1498177Y822471D03*
X1494177D03*
X1487559Y846065D03*
X1491959D03*
X1496359D03*
X1486973Y1572121D03*
X1491698D03*
X1496422D03*
X1508757Y542960D03*
X1500757D03*
X1504757D03*
X1512757D03*
X1509405Y716777D03*
X1500759Y846065D03*
X1510595Y1572121D03*
X1501147D03*
X1516757Y542960D03*
X1514722Y710454D03*
X1515320Y1572121D03*
X1524769D03*
X1520044D03*
X1542205Y716777D03*
X1539782Y1238414D03*
X1529493Y1572121D03*
X1534824D03*
X1547522Y710454D03*
X1555603Y791891D03*
X1550432Y791809D03*
X1543772Y1238384D03*
X1567836Y573930D03*
X1559618Y791857D03*
X1569148Y1344681D03*
X1572924D03*
X1572906Y1359161D03*
X1580652Y688514D03*
X1575335Y694837D03*
X1579205Y1306052D03*
X1580924Y1344681D03*
Y1359161D03*
X1586688Y1572121D03*
X1592852Y1304041D03*
X1596138Y1572121D03*
X1600862D03*
X1591413D03*
X1609141Y598389D03*
X1613422Y654745D03*
X1608105Y661068D03*
X1608652Y1292296D03*
Y1300646D03*
X1610311Y1572121D03*
X1615035D03*
X1605587D03*
X1620379Y550418D03*
X1624484Y1572121D03*
X1619760D03*
X1629209D03*
X1646422Y635745D03*
X1641105Y642068D03*
X1643382Y1572121D03*
X1638657D03*
X1655147Y679791D03*
X1657555Y1572121D03*
X1652831D03*
X1648106D03*
X1662886D03*
X1690560Y430095D03*
X1680147Y1311041D03*
X1685383Y1719651D03*
Y1726651D03*
X1712799Y107335D03*
X1710230Y1726333D03*
X1750463Y1649448D03*
X1762062Y43086D03*
X1755463Y1649448D03*
X1773757Y34383D03*
X1777754Y43352D03*
X1773554Y43192D03*
X1769900D03*
X1781990Y43238D03*
X1787672Y53069D03*
X1791672D03*
X1807296Y260516D03*
G54D25*
X48333Y444958D03*
X46759D03*
Y439446D03*
X48333D03*
G54D34*
X194084Y1500445D03*
X219280D03*
X231370D03*
X256566D03*
X322146D03*
X347342D03*
X359432D03*
X384628D03*
X458257D03*
X483453D03*
X495543D03*
X520739D03*
X586319D03*
X611515D03*
X623605D03*
X648801D03*
X1201957Y1533445D03*
X1227153D03*
X1239243D03*
X1264439D03*
X1330019D03*
X1355215D03*
X1367305D03*
X1392501D03*
X1466131D03*
X1491327D03*
X1503417D03*
X1528613D03*
X1594193D03*
X1619389D03*
X1631479D03*
X1656675D03*
G54D71*
X716269Y448279D03*
X719419D03*
X716269Y452844D03*
X719419D03*
X716269Y457649D03*
X719419D03*
X735086Y441981D03*
Y452844D03*
X738236Y441981D03*
Y452844D03*
G54D44*
X403312Y1000704D03*
X447400Y968982D03*
X1379498Y1000714D03*
X1423542Y968981D03*
G54D53*
X433030Y981272D03*
X1408936D03*
G54D26*
X39361Y539285D03*
X46361D03*
X65823Y758505D03*
X67522Y1564789D03*
Y1557889D03*
X67435Y1578558D03*
X67522Y1571689D03*
X54927Y1648887D03*
X61927D03*
X81965Y758505D03*
X72823D03*
X74522Y1564789D03*
Y1557889D03*
X74435Y1578558D03*
X74522Y1571689D03*
X88965Y758505D03*
X95524D03*
X111666D03*
X102524D03*
X125225D03*
X118666D03*
X117190Y1390210D03*
X124190D03*
X141367Y758505D03*
X132225D03*
X134685Y1672333D03*
X141685D03*
X148367Y758505D03*
X154926D03*
X171068D03*
X161926D03*
X184626D03*
X178068D03*
X177322Y1502450D03*
X184322D03*
X200768Y758505D03*
X191626D03*
X207768D03*
X214327D03*
X227415Y597556D03*
Y589456D03*
X227433Y605598D03*
X230469Y758505D03*
X221327D03*
X234415Y597556D03*
Y589456D03*
X234433Y605598D03*
X237469Y758505D03*
X253166Y67826D03*
X260166D03*
X251969Y78930D03*
X258969D03*
X271546Y1535721D03*
Y1542575D03*
X278546Y1535721D03*
X291568Y1537746D03*
X291542Y1530892D03*
X278546Y1542575D03*
X303872Y1500938D03*
X298568Y1537746D03*
X298542Y1530892D03*
X310872Y1500938D03*
X406608Y1535721D03*
X399608D03*
X406608Y1542575D03*
X399608D03*
X439902Y1501267D03*
X427653Y1530892D03*
X434653D03*
X427679Y1537746D03*
X434679D03*
X451599Y120007D03*
X446902Y1501267D03*
X458599Y120007D03*
X508723Y285010D03*
X515723D03*
X508723Y301115D03*
X515723D03*
X508723Y293060D03*
X515723D03*
X508723Y309170D03*
X515723D03*
X542619Y1535721D03*
X535619D03*
X542619Y1542575D03*
X535619D03*
X555741Y1537746D03*
X555715Y1530892D03*
X568142Y1501985D03*
X575142D03*
X562741Y1537746D03*
X562715Y1530892D03*
X595723Y294010D03*
X602723D03*
X595723Y310115D03*
X602723D03*
X595723Y302060D03*
X602723D03*
X595723Y318170D03*
X602723D03*
X643855Y758505D03*
X650855D03*
X659997D03*
X673556D03*
X666997D03*
X685420Y97062D03*
X692420D03*
X680556Y758505D03*
X689698D03*
X703257D03*
X696698D03*
X710257D03*
X719399D03*
X726399D03*
X732957D03*
X725641Y1408138D03*
X732641D03*
X725500Y1415500D03*
X732500D03*
X725500Y1430150D03*
X732500D03*
X749099Y758505D03*
X739957D03*
X756099D03*
X762658D03*
X769658D03*
X778800D03*
X783673Y1355396D03*
Y1362296D03*
X792359Y758504D03*
X785800Y758505D03*
X790673Y1355396D03*
Y1362296D03*
X799359Y758504D03*
X808500D03*
X815500D03*
X1018144Y1284787D03*
X1011144D03*
X1048965Y758504D03*
X1041965D03*
X1058107D03*
X1065107D03*
X1078666D03*
X1071666D03*
X1087808D03*
X1094808D03*
X1108367D03*
X1101367D03*
X1117509D03*
X1124509D03*
X1138068D03*
X1131068D03*
X1147210D03*
X1154210D03*
X1167768D03*
X1160768D03*
X1176910D03*
X1183910D03*
X1183752Y1533247D03*
X1197469Y758504D03*
X1190469D03*
X1190752Y1533247D03*
X1206611Y758504D03*
X1213611D03*
X1286419Y1568721D03*
X1279419D03*
X1286419Y1575575D03*
X1279419D03*
X1299415Y1563892D03*
X1299441Y1570746D03*
X1320436Y614409D03*
Y607309D03*
X1311852Y1535345D03*
X1318852D03*
X1306415Y1563892D03*
X1306441Y1570746D03*
X1327436Y614409D03*
Y607309D03*
X1407481Y1568721D03*
Y1575575D03*
X1414481Y1568721D03*
Y1575575D03*
X1435527Y1563892D03*
X1435553Y1570746D03*
X1448082Y1535743D03*
X1455082D03*
X1442527Y1563892D03*
X1442553Y1570746D03*
X1543593Y1568721D03*
Y1575575D03*
X1555087Y671098D03*
X1550593Y1568721D03*
Y1575575D03*
X1562087Y671098D03*
X1563589Y1563892D03*
X1570589D03*
X1563615Y1570746D03*
X1570615D03*
X1575992Y1535571D03*
X1582992D03*
X1626996Y758504D03*
X1619996D03*
X1636138D03*
X1643138D03*
X1656697D03*
X1649697D03*
X1665839D03*
X1672839D03*
X1673258Y1411694D03*
X1686398Y758504D03*
X1679398D03*
X1680258Y1411694D03*
X1695540Y758504D03*
X1702540D03*
X1716099D03*
X1709099D03*
X1730096Y63051D03*
X1737096D03*
X1729389Y86348D03*
X1736389D03*
X1725241Y758504D03*
X1732241D03*
X1733500Y1402500D03*
X1726500D03*
X1745799Y758504D03*
X1738799D03*
X1754941D03*
X1761941D03*
X1757279Y1597550D03*
X1764279D03*
X1757279Y1604950D03*
X1764279D03*
X1775500Y758504D03*
X1768500D03*
X1784642D03*
X1791642D03*
X1808013Y1598316D03*
X1801013D03*
X1808013Y1605816D03*
X1801013D03*
G54D35*
X187673Y1656735D03*
X195153D03*
X187673Y1671753D03*
X195153D03*
X187673Y1659294D03*
X195153Y1661853D03*
Y1659294D03*
X187673Y1661853D03*
Y1674312D03*
X195153Y1676871D03*
Y1674312D03*
X187673Y1676871D03*
X187820Y1686870D03*
Y1689429D03*
X195300Y1686870D03*
Y1691988D03*
Y1689429D03*
X187820Y1691988D03*
Y1701988D03*
Y1704547D03*
X195300Y1701988D03*
Y1707106D03*
Y1704547D03*
X187820Y1707106D03*
X394186Y1670218D03*
Y1675336D03*
Y1672777D03*
X401666Y1670218D03*
Y1672777D03*
Y1675336D03*
X444760Y1641441D03*
X452240D03*
X444760Y1646559D03*
Y1644000D03*
X452240D03*
Y1646559D03*
X663198Y1700695D03*
Y1698136D03*
X655718Y1700695D03*
Y1695577D03*
Y1698136D03*
X663198Y1695577D03*
Y1714695D03*
Y1712136D03*
X655718Y1714695D03*
Y1709577D03*
Y1712136D03*
X663198Y1709577D03*
X1209176Y292066D03*
Y289507D03*
Y286948D03*
X1225176Y292066D03*
Y289507D03*
Y286948D03*
X1216656D03*
Y289507D03*
Y292066D03*
X1243325Y300157D03*
X1235845D03*
X1232656Y286948D03*
Y289507D03*
Y292066D03*
X1243325Y302716D03*
Y305275D03*
X1235845D03*
Y302716D03*
X1257176Y292066D03*
Y289507D03*
Y286948D03*
X1273176Y292066D03*
Y289507D03*
Y286948D03*
X1264656D03*
Y289507D03*
Y292066D03*
X1289176D03*
Y289507D03*
Y286948D03*
X1280656D03*
Y289507D03*
Y292066D03*
X1304594Y298066D03*
X1296656Y286948D03*
Y289507D03*
Y292066D03*
X1304594Y303184D03*
Y300625D03*
X1305176Y292066D03*
Y289507D03*
Y286948D03*
X1312656D03*
Y289507D03*
Y292066D03*
X1312074Y298066D03*
Y300625D03*
Y303184D03*
X1329176Y292066D03*
Y289507D03*
Y286948D03*
X1345176Y292066D03*
Y289507D03*
Y286948D03*
X1336656D03*
Y289507D03*
Y292066D03*
X1361176D03*
Y289507D03*
Y286948D03*
X1352656D03*
Y289507D03*
Y292066D03*
X1368656Y286948D03*
Y289507D03*
Y292066D03*
X1394945Y1641681D03*
X1402425D03*
X1394945Y1644240D03*
X1402425Y1646799D03*
Y1644240D03*
X1394945Y1646799D03*
X1705370Y1718475D03*
Y1721034D03*
Y1723593D03*
X1697890D03*
Y1721034D03*
Y1718475D03*
G54D80*
X872087Y1312091D03*
Y1327446D03*
Y1324886D03*
Y1322327D03*
Y1319768D03*
Y1317209D03*
Y1314650D03*
Y1340241D03*
Y1337682D03*
Y1335123D03*
Y1332564D03*
Y1330005D03*
X894135Y1312091D03*
Y1314650D03*
Y1317209D03*
Y1319768D03*
Y1322327D03*
Y1324886D03*
Y1327446D03*
Y1330005D03*
Y1332564D03*
Y1335123D03*
Y1337682D03*
Y1340241D03*
X962459Y1312091D03*
Y1327446D03*
Y1324886D03*
Y1322327D03*
Y1319768D03*
Y1317209D03*
Y1314650D03*
Y1340241D03*
Y1337682D03*
Y1335123D03*
Y1332564D03*
Y1330005D03*
X984507Y1312091D03*
Y1314650D03*
Y1317209D03*
Y1319768D03*
Y1322327D03*
Y1324886D03*
Y1327446D03*
Y1330005D03*
Y1332564D03*
Y1335123D03*
Y1337682D03*
Y1340241D03*
G54D62*
X632848Y1644704D03*
X627808D03*
X632848Y1642736D03*
X627808D03*
X914243Y977491D03*
Y979459D03*
X919283Y977491D03*
Y979459D03*
X1172934Y1673382D03*
X1177974D03*
X1172934Y1675350D03*
X1177974D03*
X1658515Y1679197D03*
Y1681165D03*
X1663555Y1679197D03*
Y1681165D03*
G54D17*
X30771Y441130D03*
Y445519D03*
X38149Y1603396D03*
Y1623196D03*
X62329Y388462D03*
X62327Y393079D03*
X57738Y528205D03*
X57943Y1654387D03*
X80875Y763766D03*
X78516Y1444500D03*
Y1448500D03*
X79183Y1629905D03*
X110576Y763766D03*
X100576D03*
X127016Y1436500D03*
X140408Y763700D03*
X130277Y763766D03*
X137516Y1425000D03*
X134516Y1429000D03*
X170078Y763666D03*
X159916Y763766D03*
X199778D03*
X189678D03*
X200939Y1658170D03*
X200597Y1664479D03*
X204675Y751266D03*
X207774Y1658192D03*
X207546Y1664479D03*
X219279Y763766D03*
X227631Y960966D03*
X232379Y763766D03*
X255916Y58400D03*
Y62400D03*
X247313Y111743D03*
X263087Y775410D03*
Y784788D03*
Y780588D03*
X274787Y793988D03*
Y797988D03*
X288657Y37420D03*
X336516Y582500D03*
Y578500D03*
X345673Y591335D03*
Y586415D03*
X353673Y558415D03*
Y562415D03*
Y570415D03*
Y574415D03*
X357854Y1198131D03*
X370309Y239452D03*
X366316Y544000D03*
Y548000D03*
X370447Y1192148D03*
X370516Y1187862D03*
Y1195862D03*
X370407Y1207538D03*
X386726Y1003766D03*
X386287Y1037488D03*
X393287Y1043488D03*
X386287Y1031288D03*
Y1043488D03*
X393287Y1031288D03*
Y1037488D03*
X386132Y1049766D03*
X388132Y1053266D03*
X393675Y1056766D03*
X391675Y1060266D03*
X382733Y1670046D03*
Y1673985D03*
X397673Y573415D03*
X401673Y577415D03*
X409175Y997766D03*
Y991266D03*
X399675Y1007266D03*
Y1028266D03*
X402675Y1040766D03*
X410175D03*
X399675Y1034266D03*
X395675Y1047266D03*
X402675Y1053266D03*
X410175D03*
X403175Y1060266D03*
X401175Y1056766D03*
X395675Y1053266D03*
X408675Y1056766D03*
X410175Y1047266D03*
X403175D03*
X410016Y1672500D03*
X412787Y966488D03*
X412675Y978266D03*
X424287Y985266D03*
X416675Y991266D03*
X424175D03*
X416675Y997766D03*
X424175D03*
X417675Y1040766D03*
X425175D03*
X415682Y1032304D03*
X417675Y1053266D03*
X416175Y1056766D03*
X425175Y1053266D03*
X423175Y1056766D03*
X414175Y1060266D03*
X425175Y1047266D03*
X417675D03*
X414287Y1071988D03*
X424336Y1615168D03*
X414016Y1653500D03*
X425687Y970088D03*
X431175Y985266D03*
Y997766D03*
Y991266D03*
X439675Y1042766D03*
Y1038766D03*
X430675Y1056766D03*
X432675Y1053266D03*
X432175Y1047266D03*
X427287Y1068488D03*
X426993Y1608370D03*
X436016Y1626000D03*
X439016Y1630000D03*
X446709Y106490D03*
Y102490D03*
X447675Y981766D03*
X446175Y985266D03*
X455175Y981766D03*
X453675Y997766D03*
Y991266D03*
X455175Y987766D03*
X446175Y997766D03*
Y991266D03*
X454675Y1040766D03*
X447465Y1053266D03*
X449175Y1056766D03*
X454946Y1053266D03*
X447175Y1047266D03*
X454675D03*
X457287Y966488D03*
X470175Y981766D03*
X457175Y978266D03*
X462675Y981766D03*
X460675Y991266D03*
Y997766D03*
X462675Y987766D03*
X470175D03*
X468175Y997766D03*
Y991266D03*
X462672Y1013604D03*
Y1009864D03*
Y1006123D03*
Y1017344D03*
Y1024824D03*
Y1028564D03*
Y1021084D03*
Y1032304D03*
X462175Y1040766D03*
X469675D03*
X462175Y1047266D03*
X469675D03*
X456675Y1056766D03*
X462426Y1053266D03*
X464175Y1056766D03*
X469675Y1053145D03*
X458675Y1060266D03*
X458287Y1071988D03*
X474934Y285693D03*
X479551Y966489D03*
X477675Y981766D03*
X479251Y978266D03*
X477675Y1000766D03*
Y994266D03*
Y987766D03*
X477594Y1015474D03*
X477675Y1007266D03*
X480675Y1027745D03*
X477594Y1019017D03*
Y1022560D03*
X484175Y1040766D03*
X478613Y1037266D03*
X482223Y1031245D03*
X476675Y1040766D03*
X484175Y1047266D03*
X477175D03*
X484175Y1053145D03*
X471175Y1056766D03*
X476675Y1053145D03*
X478675Y1056766D03*
X480787Y1071988D03*
X496058Y143545D03*
Y147545D03*
Y138598D03*
X490551Y978266D03*
X485175Y981766D03*
X492175D03*
Y994266D03*
X485175Y1000766D03*
X492175D03*
Y987766D03*
X485175Y994266D03*
Y987766D03*
Y1007266D03*
Y1015474D03*
X492175D03*
Y1007266D03*
X488175Y1027745D03*
X492175Y1022560D03*
X485175Y1019017D03*
Y1022560D03*
X492175Y1019017D03*
X488175Y1034745D03*
X489624Y1031245D03*
X491175Y1040766D03*
X491675Y1053145D03*
X486175Y1056766D03*
X491675Y1047266D03*
X507592Y128498D03*
Y136498D03*
Y132498D03*
X529383Y161919D03*
Y157919D03*
Y166937D03*
X534107Y133207D03*
Y149207D03*
Y137207D03*
Y141207D03*
Y145207D03*
Y153207D03*
X563089Y321993D03*
X570237Y1268118D03*
X581675Y1238075D03*
X588675Y1234075D03*
X613287Y1262988D03*
X613297Y1270888D03*
Y1274798D03*
X631161Y70040D03*
Y66040D03*
X645618Y444936D03*
X644471Y473877D03*
X644433Y469827D03*
X648846Y763766D03*
X645467Y1370789D03*
Y1380953D03*
Y1374914D03*
X643458Y1636815D03*
X656454Y453880D03*
X653006Y751266D03*
X659037Y763766D03*
X658087Y960966D03*
X659683Y1380836D03*
Y1376836D03*
X657483Y1645522D03*
X650483D03*
X672512Y417859D03*
X672516Y433862D03*
X672866Y429352D03*
X672666Y447202D03*
X672516Y441862D03*
X672566Y437732D03*
X672516Y457862D03*
Y453862D03*
Y465862D03*
X678547Y763766D03*
X677477Y1642042D03*
Y1629042D03*
X676913Y1646419D03*
X668316Y1700164D03*
X680460Y75627D03*
X688738Y763766D03*
X687788Y960966D03*
X683016Y1654500D03*
X689331Y1684735D03*
X700254Y524700D03*
X708248Y763766D03*
X696462Y1658337D03*
X718439Y763766D03*
X717489Y960966D03*
X719637Y1574283D03*
X718517Y1670830D03*
X725516Y380862D03*
X737948Y763766D03*
X724266Y1566333D03*
X725607Y1647997D03*
Y1652997D03*
X735016Y1663000D03*
X725634Y1685660D03*
X738242Y1688839D03*
X751244Y277399D03*
X746072Y573171D03*
X753006Y751266D03*
X748140Y763766D03*
X747190Y960966D03*
X742016Y1663000D03*
X754393Y273399D03*
X757555Y286632D03*
X767649Y763766D03*
X776168Y411344D03*
Y407344D03*
Y415344D03*
X775168Y419344D03*
Y427344D03*
X779768Y438504D03*
X774118Y446564D03*
X774016Y442500D03*
X777991Y763766D03*
X776891Y960966D03*
X798016Y295488D03*
X797907Y304062D03*
X789668Y475344D03*
X797350Y763765D03*
X803393Y268621D03*
X801186Y312773D03*
X806178Y508166D03*
X810411Y763765D03*
Y767665D03*
Y771465D03*
X806591Y960966D03*
X819230Y1486876D03*
Y1490876D03*
Y1496876D03*
Y1500876D03*
Y1506284D03*
Y1516284D03*
Y1510284D03*
Y1520284D03*
Y1530284D03*
Y1526284D03*
X842736Y220362D03*
X838095Y1281324D03*
X838223Y1285472D03*
X839529Y1291772D03*
X839525Y1296068D03*
X849736Y209362D03*
X849636Y216362D03*
X847025Y287602D03*
X849266Y1269785D03*
X849410Y1287438D03*
X889723Y1141058D03*
X897664Y1143953D03*
X911016Y853000D03*
X904016Y945000D03*
X930311Y193386D03*
X930111Y189386D03*
X928441Y201612D03*
X943016Y850500D03*
X935016Y894500D03*
X934016Y973500D03*
Y986500D03*
X936748Y1141058D03*
X944689Y1143953D03*
X935152Y1265636D03*
Y1282115D03*
X935199Y1278059D03*
X935117Y1269729D03*
X935223Y1273958D03*
X935056Y1294191D03*
X935136Y1290152D03*
X935172Y1286156D03*
X961016Y903500D03*
X958016Y1267000D03*
Y1279000D03*
Y1275000D03*
Y1271000D03*
X1008093Y1294268D03*
X1046956Y763765D03*
X1057148D03*
X1076657D03*
X1086849D03*
X1106357D03*
X1116550D03*
X1136058D03*
X1132323Y1649775D03*
X1136480Y1682518D03*
X1129025Y1682565D03*
Y1686065D03*
X1140016Y1679000D03*
X1146251Y763765D03*
X1165759D03*
X1180817Y751265D03*
X1175951Y763765D03*
X1195460D03*
X1208521D03*
X1203773Y960965D03*
X1229016Y1417000D03*
X1249313Y787397D03*
X1269693Y774324D03*
Y770324D03*
X1271693Y783324D03*
Y787324D03*
X1261693Y777824D03*
Y781824D03*
X1286768Y801299D03*
X1333693Y1203988D03*
X1333748Y1228559D03*
X1342907Y1224309D03*
X1362868Y1003765D03*
X1362193Y1030988D03*
Y1043488D03*
Y1037488D03*
X1364317Y1053265D03*
X1362817Y1049765D03*
X1360827Y1214637D03*
X1375817Y1007265D03*
X1369193Y1030988D03*
X1375817Y1028265D03*
X1369193Y1043488D03*
Y1037488D03*
X1375817Y1034265D03*
X1378817Y1040765D03*
X1379317Y1047265D03*
X1371817D03*
X1377317Y1056765D03*
X1371817Y1053265D03*
X1379317Y1060265D03*
X1378817Y1053265D03*
X1389193Y966488D03*
X1388817Y978265D03*
X1385317Y991265D03*
Y997765D03*
X1392817Y991265D03*
Y997765D03*
X1391824Y1032303D03*
X1386317Y1040765D03*
X1393817D03*
X1386317Y1047265D03*
X1393817D03*
Y1053265D03*
X1386317D03*
X1392317Y1056765D03*
X1384817D03*
X1390317Y1060265D03*
X1390193Y1071988D03*
X1401693Y969988D03*
X1407317Y985265D03*
X1400413D03*
X1407317Y991265D03*
X1400317D03*
Y997765D03*
X1407317D03*
X1401317Y1040765D03*
X1408317Y1047265D03*
X1401317D03*
X1408817Y1053265D03*
X1401317D03*
X1399317Y1056765D03*
X1406817D03*
X1402893Y1068488D03*
X1422317Y985265D03*
X1423915Y981765D03*
X1422317Y997765D03*
Y991265D03*
X1415817Y1038765D03*
Y1042765D03*
X1423317Y1047265D03*
X1423607Y1053265D03*
X1433193Y966488D03*
X1438817Y981765D03*
X1433317Y978265D03*
X1431317Y981765D03*
Y987765D03*
X1436817Y997765D03*
X1438817Y987765D03*
X1429817Y991265D03*
X1436817D03*
X1429817Y997765D03*
X1438814Y1013603D03*
Y1006122D03*
Y1009863D03*
Y1028563D03*
Y1017343D03*
Y1021083D03*
Y1024823D03*
Y1032303D03*
X1438317Y1040765D03*
X1430817D03*
Y1047265D03*
X1438317D03*
X1438568Y1053265D03*
X1434817Y1060265D03*
X1425317Y1056765D03*
X1432817D03*
X1431088Y1053265D03*
X1434693Y1071988D03*
X1446043Y535318D03*
Y539318D03*
X1453517Y981765D03*
X1446317D03*
X1444317Y991265D03*
X1453817Y1000765D03*
Y987765D03*
X1444317Y997765D03*
X1453817Y994265D03*
X1446317Y987765D03*
X1453736Y1015473D03*
X1453817Y1007265D03*
X1453736Y1022559D03*
Y1019016D03*
X1445817Y1040765D03*
X1452817D03*
X1453317Y1047265D03*
X1452817Y1053144D03*
X1447317Y1056765D03*
X1440317D03*
X1445817Y1053144D03*
Y1047265D03*
X1466773Y548977D03*
Y552977D03*
Y560977D03*
Y564977D03*
X1458773Y572977D03*
Y568977D03*
Y576977D03*
Y580977D03*
X1455693Y966488D03*
X1455393Y978265D03*
X1466693D03*
X1461317Y981765D03*
X1468317D03*
Y987765D03*
X1461317Y1000765D03*
X1468317Y994265D03*
Y1000765D03*
X1461317Y987765D03*
Y994265D03*
X1468317Y1015473D03*
Y1007265D03*
X1461317Y1015473D03*
Y1007265D03*
X1468317Y1019016D03*
Y1022559D03*
X1464317Y1027744D03*
X1461317Y1022559D03*
X1456817Y1027744D03*
X1461317Y1019016D03*
X1460317Y1040765D03*
X1454755Y1037265D03*
X1467317Y1040765D03*
X1458365Y1031244D03*
X1465766D03*
X1464317Y1034744D03*
X1460317Y1047265D03*
X1467817D03*
X1462317Y1056765D03*
X1456893Y1060265D03*
X1467817Y1053144D03*
X1454817Y1056765D03*
X1460317Y1053144D03*
X1456693Y1071988D03*
X1510773Y563977D03*
X1514773Y567977D03*
X1540393Y801185D03*
Y797185D03*
X1532893Y1264488D03*
X1540193D03*
X1547262Y804133D03*
X1557779Y1237662D03*
X1548268Y1268488D03*
Y1264488D03*
X1548133Y1274378D03*
X1548193Y1278988D03*
Y1282988D03*
X1547493Y1289938D03*
X1569609Y804063D03*
X1564614Y792552D03*
Y796552D03*
X1565193Y1234162D03*
X1560693Y1284108D03*
X1569518Y1299568D03*
X1576319Y1239866D03*
X1582463Y1256688D03*
Y1268388D03*
X1574153Y1286088D03*
X1576518Y1299568D03*
X1599693Y1274988D03*
Y1278988D03*
X1588993Y1295288D03*
Y1291288D03*
X1599693Y1286988D03*
X1599767Y1302895D03*
X1607460Y556730D03*
X1628817Y752765D03*
X1624987Y763765D03*
X1635179D03*
X1634229Y960965D03*
X1654688Y763765D03*
X1654086Y1416284D03*
X1657910Y1426945D03*
X1664880Y763765D03*
X1663930Y960965D03*
X1666351Y1416710D03*
X1670353Y1426686D03*
X1677791Y121762D03*
X1687441Y153762D03*
Y161762D03*
X1684389Y763765D03*
X1694581D03*
X1693631Y960965D03*
X1714090Y763765D03*
X1732381Y53651D03*
Y57651D03*
X1724282Y763765D03*
X1723332Y960965D03*
X1726979Y1663465D03*
Y1667965D03*
Y1658965D03*
X1743791Y763765D03*
X1753983D03*
X1753033Y960965D03*
X1760945Y1658956D03*
X1773491Y763765D03*
X1768779Y1676865D03*
X1786006Y46086D03*
X1783683Y763765D03*
X1782733Y960965D03*
X1811138Y174869D03*
G54D72*
X722642Y438831D03*
Y441981D03*
X719418Y438831D03*
Y441981D03*
X725718Y438831D03*
Y441981D03*
X730152Y457649D03*
Y460799D03*
X725718Y457649D03*
Y460799D03*
G54D36*
X277098Y185236D03*
X395208D03*
G54D54*
X514398Y193318D03*
Y196468D03*
Y199618D03*
Y196468D03*
X608572Y35750D03*
Y32600D03*
Y35750D03*
Y38900D03*
X628408Y762004D03*
D03*
Y758854D03*
Y765154D03*
X634946Y761053D03*
D03*
Y757903D03*
Y764203D03*
X912500Y956075D03*
X907500D03*
X912500Y952925D03*
Y956075D03*
X907500Y952925D03*
Y956075D03*
X912500Y959225D03*
X907500D03*
X923500Y948075D03*
Y951225D03*
X928500Y948075D03*
Y951225D03*
Y948075D03*
Y944925D03*
X923500Y948075D03*
Y944925D03*
X1242461Y160385D03*
Y157235D03*
Y160385D03*
Y163535D03*
X1282028Y134848D03*
Y131698D03*
Y134848D03*
Y137998D03*
X1497177Y805913D03*
Y812213D03*
Y809063D03*
D03*
X1508177Y805913D03*
Y812213D03*
Y809063D03*
D03*
G54D63*
X659868Y1669753D03*
X666482D03*
X942951Y933979D03*
X936337D03*
G54D45*
X401679Y991763D03*
X493229Y1057203D03*
X1377995Y991723D03*
X1469435Y1057203D03*
G54D18*
X33738Y441130D03*
Y445519D03*
X41116Y1603396D03*
Y1623196D03*
X65296Y388462D03*
X65294Y393079D03*
X60705Y528205D03*
X60910Y1654387D03*
X81483Y1444500D03*
Y1448500D03*
X82150Y1629905D03*
X83842Y763766D03*
X103543D03*
X113543D03*
X133244D03*
X140483Y1425000D03*
X137483Y1429000D03*
X129983Y1436500D03*
X143375Y763700D03*
X162883Y763766D03*
X173045Y763666D03*
X192645Y763766D03*
X207642Y751266D03*
X202745Y763766D03*
X203906Y1658170D03*
X210741Y1658192D03*
X210513Y1664479D03*
X203564D03*
X222246Y763766D03*
X230598Y960966D03*
X235346Y763766D03*
X258883Y58400D03*
Y62400D03*
X250280Y111743D03*
X266054Y775410D03*
Y784788D03*
Y780588D03*
X277754Y793988D03*
Y797988D03*
X291624Y37420D03*
X339483Y582500D03*
Y578500D03*
X348640Y591335D03*
Y586415D03*
X356640Y558415D03*
Y562415D03*
Y570415D03*
Y574415D03*
X360821Y1198131D03*
X373276Y239452D03*
X369283Y544000D03*
Y548000D03*
X373414Y1192148D03*
X373483Y1187862D03*
Y1195862D03*
X373374Y1207538D03*
X389693Y1003766D03*
X389254Y1037488D03*
Y1031288D03*
Y1043488D03*
X389099Y1049766D03*
X391099Y1053266D03*
X394642Y1060266D03*
X385700Y1670046D03*
Y1673985D03*
X400640Y573415D03*
X404640Y577415D03*
X402642Y1007266D03*
Y1028266D03*
X405642Y1040766D03*
X402642Y1034266D03*
X396254Y1043488D03*
Y1031288D03*
Y1037488D03*
X398642Y1047266D03*
X405642Y1053266D03*
X406142Y1060266D03*
X396642Y1056766D03*
X404142D03*
X398642Y1053266D03*
X406142Y1047266D03*
X415754Y966488D03*
X415642Y978266D03*
X412142Y997766D03*
X419642Y991266D03*
Y997766D03*
X412142Y991266D03*
X420642Y1040766D03*
X413142D03*
X418649Y1032304D03*
X420642Y1053266D03*
X413142D03*
X419142Y1056766D03*
X417142Y1060266D03*
X411642Y1056766D03*
X420642Y1047266D03*
X413142D03*
X417254Y1071988D03*
X416983Y1653500D03*
X412983Y1672500D03*
X428654Y970088D03*
X434142Y985266D03*
X427254D03*
X434142Y997766D03*
Y991266D03*
X427142D03*
Y997766D03*
X428142Y1040766D03*
X433642Y1056766D03*
X428142Y1053266D03*
X426142Y1056766D03*
X435642Y1053266D03*
X428142Y1047266D03*
X435142D03*
X430254Y1068488D03*
X429960Y1608370D03*
X427303Y1615168D03*
X438983Y1626000D03*
X449676Y106490D03*
Y102490D03*
X450642Y981766D03*
X449142Y985266D03*
Y997766D03*
Y991266D03*
X442642Y1042766D03*
Y1038766D03*
X450432Y1053266D03*
X452142Y1056766D03*
X450142Y1047266D03*
X441983Y1630000D03*
X460254Y966488D03*
X460142Y978266D03*
X458142Y981766D03*
X465642D03*
X463642Y991266D03*
X456642Y997766D03*
X463642D03*
X465642Y987766D03*
X456642Y991266D03*
X458142Y987766D03*
X465639Y1013604D03*
Y1009864D03*
Y1006123D03*
Y1017344D03*
Y1024824D03*
Y1028564D03*
Y1021084D03*
X457642Y1040766D03*
X465639Y1032304D03*
X465142Y1040766D03*
Y1047266D03*
X459642Y1056766D03*
X465393Y1053266D03*
X467142Y1056766D03*
X461642Y1060266D03*
X457913Y1053266D03*
X457642Y1047266D03*
X461254Y1071988D03*
X477901Y285693D03*
X482518Y966489D03*
X473142Y981766D03*
X480642D03*
X482218Y978266D03*
X480642Y1000766D03*
Y994266D03*
Y987766D03*
X473142D03*
X471142Y997766D03*
Y991266D03*
X480561Y1015474D03*
X480642Y1007266D03*
X483642Y1027745D03*
X480561Y1019017D03*
Y1022560D03*
X481580Y1037266D03*
X472642Y1040766D03*
X479642D03*
X472642Y1047266D03*
X480142D03*
X474142Y1056766D03*
X479642Y1053145D03*
X481642Y1056766D03*
X472642Y1053145D03*
X483754Y1071988D03*
X499025Y143545D03*
Y147545D03*
Y138598D03*
X493518Y978266D03*
X488142Y981766D03*
X495142D03*
Y994266D03*
X488142Y1000766D03*
X495142D03*
Y987766D03*
X488142Y994266D03*
Y987766D03*
Y1007266D03*
Y1015474D03*
X495142D03*
Y1007266D03*
X491142Y1027745D03*
X495142Y1022560D03*
X488142Y1019017D03*
Y1022560D03*
X495142Y1019017D03*
X487142Y1040766D03*
X485190Y1031245D03*
X491142Y1034745D03*
X492591Y1031245D03*
X494142Y1040766D03*
X487142Y1047266D03*
Y1053145D03*
X494642D03*
X489142Y1056766D03*
X494642Y1047266D03*
X510559Y128498D03*
Y136498D03*
Y132498D03*
X537074Y133207D03*
Y149207D03*
Y137207D03*
Y141207D03*
Y145207D03*
Y153207D03*
X532350Y161919D03*
Y157919D03*
Y166937D03*
X566056Y321993D03*
X573204Y1268118D03*
X584642Y1238075D03*
X591642Y1234075D03*
X616254Y1262988D03*
X616264Y1270888D03*
Y1274798D03*
X634128Y70040D03*
Y66040D03*
X648585Y444936D03*
X647438Y473877D03*
X647400Y469827D03*
X648434Y1370789D03*
Y1380953D03*
Y1374914D03*
X646425Y1636815D03*
X659421Y453880D03*
X655973Y751266D03*
X662004Y763766D03*
X651813D03*
X661054Y960966D03*
X662650Y1380836D03*
Y1376836D03*
X660450Y1645522D03*
X653450D03*
X675479Y417859D03*
X675483Y433862D03*
X675833Y429352D03*
X675633Y447202D03*
X675483Y441862D03*
X675533Y437732D03*
X675483Y457862D03*
Y453862D03*
Y465862D03*
X671283Y1700164D03*
X683427Y75627D03*
X691705Y763766D03*
X681514D03*
X690755Y960966D03*
X680444Y1642042D03*
Y1629042D03*
X685983Y1654500D03*
X679880Y1646419D03*
X692298Y1684735D03*
X703221Y524700D03*
X699429Y1658337D03*
X721406Y763766D03*
X711215D03*
X720456Y960966D03*
X722604Y1574283D03*
X721484Y1670830D03*
X728483Y380862D03*
X727233Y1566333D03*
X728574Y1647997D03*
Y1652997D03*
X737983Y1663000D03*
X728601Y1685660D03*
X749039Y573171D03*
X751107Y763766D03*
X740915D03*
X750157Y960966D03*
X744983Y1663000D03*
X741209Y1688839D03*
X754211Y277399D03*
X757360Y273399D03*
X760522Y286632D03*
X755973Y751266D03*
X779135Y411344D03*
Y407344D03*
Y415344D03*
X778135Y419344D03*
Y427344D03*
X782735Y438504D03*
X777085Y446564D03*
X776983Y442500D03*
X780958Y763766D03*
X770616D03*
X779858Y960966D03*
X792635Y475344D03*
X806360Y268621D03*
X800983Y295488D03*
X804153Y312773D03*
X800874Y304062D03*
X809145Y508166D03*
X800317Y763765D03*
X809558Y960966D03*
X813378Y763765D03*
Y767665D03*
Y771465D03*
X822197Y1486876D03*
Y1490876D03*
Y1496876D03*
Y1500876D03*
Y1506284D03*
Y1516284D03*
Y1510284D03*
Y1520284D03*
Y1530284D03*
Y1526284D03*
X841062Y1281324D03*
X841190Y1285472D03*
X842496Y1291772D03*
X842492Y1296068D03*
X852703Y209362D03*
X852603Y216362D03*
X845703Y220362D03*
X849992Y287602D03*
X852233Y1269785D03*
X852377Y1287438D03*
X892690Y1141058D03*
X900631Y1143953D03*
X913983Y853000D03*
X906983Y945000D03*
X931408Y201612D03*
X933278Y193386D03*
X933078Y189386D03*
X945983Y850500D03*
X937983Y894500D03*
X936983Y973500D03*
Y986500D03*
X939715Y1141058D03*
X938119Y1265636D03*
Y1282115D03*
X938166Y1278059D03*
X938084Y1269729D03*
X938190Y1273958D03*
X938023Y1294191D03*
X938103Y1290152D03*
X938139Y1286156D03*
X947656Y1143953D03*
X960983Y1267000D03*
Y1279000D03*
Y1275000D03*
Y1271000D03*
X963983Y903500D03*
X1011060Y1294268D03*
X1049923Y763765D03*
X1060115D03*
X1079624D03*
X1089816D03*
X1109324D03*
X1119517D03*
X1139025D03*
X1135290Y1649775D03*
X1139447Y1682518D03*
X1131992Y1682565D03*
Y1686065D03*
X1149218Y763765D03*
X1142983Y1679000D03*
X1168726Y763765D03*
X1183784Y751265D03*
X1178918Y763765D03*
X1198427D03*
X1211488D03*
X1206740Y960965D03*
X1231983Y1417000D03*
X1252280Y787397D03*
X1272660Y774324D03*
Y770324D03*
X1274660Y783324D03*
Y787324D03*
X1264660Y777824D03*
Y781824D03*
X1289735Y801299D03*
X1336660Y1203988D03*
X1345874Y1224309D03*
X1336715Y1228559D03*
X1363794Y1214637D03*
X1378784Y1007265D03*
X1365835Y1003765D03*
X1372160Y1030988D03*
X1365160D03*
X1378784Y1028265D03*
X1372160Y1043488D03*
X1365160D03*
Y1037488D03*
X1372160D03*
X1378784Y1034265D03*
X1367284Y1053265D03*
X1365784Y1049765D03*
X1374784Y1047265D03*
Y1053265D03*
X1392160Y966488D03*
X1391784Y978265D03*
X1388284Y991265D03*
Y997765D03*
X1389284Y1040765D03*
X1381784D03*
X1389284Y1047265D03*
X1382284D03*
X1380284Y1056765D03*
X1389284Y1053265D03*
X1387784Y1056765D03*
X1393284Y1060265D03*
X1382284D03*
X1381784Y1053265D03*
X1393160Y1071988D03*
X1404660Y969988D03*
X1403380Y985265D03*
X1403284Y991265D03*
X1395784D03*
Y997765D03*
X1403284D03*
X1394791Y1032303D03*
X1404284Y1040765D03*
X1396784D03*
Y1047265D03*
X1404284D03*
X1396784Y1053265D03*
X1395284Y1056765D03*
X1404284Y1053265D03*
X1402284Y1056765D03*
X1405860Y1068488D03*
X1410284Y985265D03*
Y991265D03*
Y997765D03*
X1418784Y1038765D03*
Y1042765D03*
X1411284Y1047265D03*
X1411784Y1053265D03*
X1409784Y1056765D03*
X1436160Y966488D03*
X1425284Y985265D03*
X1426882Y981765D03*
X1436284Y978265D03*
X1434284Y981765D03*
Y987765D03*
X1425284Y997765D03*
X1432784Y991265D03*
X1425284D03*
X1432784Y997765D03*
X1433784Y1040765D03*
Y1047265D03*
X1426284D03*
X1437784Y1060265D03*
X1428284Y1056765D03*
X1435784D03*
X1434055Y1053265D03*
X1426574D03*
X1437660Y1071988D03*
X1449010Y535318D03*
Y539318D03*
X1441784Y981765D03*
X1449284D03*
X1447284Y991265D03*
X1439784Y997765D03*
X1441784Y987765D03*
X1439784Y991265D03*
X1447284Y997765D03*
X1449284Y987765D03*
X1441781Y1013603D03*
Y1006122D03*
Y1009863D03*
Y1028563D03*
Y1017343D03*
Y1021083D03*
Y1024823D03*
Y1032303D03*
X1441284Y1040765D03*
X1448784D03*
X1441284Y1047265D03*
X1441535Y1053265D03*
X1450284Y1056765D03*
X1443284D03*
X1448784Y1053144D03*
Y1047265D03*
X1461740Y572977D03*
Y568977D03*
Y576977D03*
Y580977D03*
X1458660Y966488D03*
X1458360Y978265D03*
X1456484Y981765D03*
X1464284D03*
X1456784Y1000765D03*
X1464284D03*
X1456784Y987765D03*
X1464284D03*
Y994265D03*
X1456784D03*
X1456703Y1015473D03*
X1464284D03*
Y1007265D03*
X1456784D03*
X1456703Y1022559D03*
X1467284Y1027744D03*
X1464284Y1022559D03*
X1456703Y1019016D03*
X1459784Y1027744D03*
X1464284Y1019016D03*
X1463284Y1040765D03*
X1457722Y1037265D03*
X1455784Y1040765D03*
X1461332Y1031244D03*
X1468733D03*
X1467284Y1034744D03*
X1463284Y1047265D03*
X1456284D03*
X1465284Y1056765D03*
X1455784Y1053144D03*
X1459860Y1060265D03*
X1457784Y1056765D03*
X1463284Y1053144D03*
X1459660Y1071988D03*
X1469740Y548977D03*
Y552977D03*
Y560977D03*
Y564977D03*
X1469660Y978265D03*
X1471284Y981765D03*
Y987765D03*
Y994265D03*
Y1000765D03*
Y1015473D03*
Y1007265D03*
Y1019016D03*
Y1022559D03*
X1470284Y1040765D03*
X1470784Y1047265D03*
Y1053144D03*
X1513740Y563977D03*
X1517740Y567977D03*
X1543360Y801185D03*
Y797185D03*
X1535860Y1264488D03*
X1543160D03*
X1550229Y804133D03*
X1551235Y1268488D03*
Y1264488D03*
X1551100Y1274378D03*
X1551160Y1278988D03*
Y1282988D03*
X1550460Y1289938D03*
X1572576Y804063D03*
X1567581Y792552D03*
Y796552D03*
X1560746Y1237662D03*
X1568160Y1234162D03*
X1563660Y1284108D03*
X1572485Y1299568D03*
X1579286Y1239866D03*
X1585430Y1256688D03*
Y1268388D03*
X1577120Y1286088D03*
X1579485Y1299568D03*
X1602660Y1274988D03*
Y1278988D03*
X1591960Y1295288D03*
Y1291288D03*
X1602660Y1286988D03*
X1602734Y1302895D03*
X1610427Y556730D03*
X1631784Y752765D03*
X1627954Y763765D03*
X1638146D03*
X1637196Y960965D03*
X1657655Y763765D03*
X1657053Y1416284D03*
X1660877Y1426945D03*
X1667847Y763765D03*
X1666897Y960965D03*
X1669318Y1416710D03*
X1673320Y1426686D03*
X1680758Y121762D03*
X1690408Y153762D03*
Y161762D03*
X1687356Y763765D03*
X1697548D03*
X1696598Y960965D03*
X1717057Y763765D03*
X1735348Y53651D03*
Y57651D03*
X1727249Y763765D03*
X1726299Y960965D03*
X1729946Y1663465D03*
Y1667965D03*
Y1658965D03*
X1746758Y763765D03*
X1756950D03*
X1756000Y960965D03*
X1763912Y1658956D03*
X1776458Y763765D03*
X1771746Y1676865D03*
X1788973Y46086D03*
X1786650Y763765D03*
X1785700Y960965D03*
X1814105Y174869D03*
G54D90*
X1225530Y60384D03*
X1233404D03*
X1241278D03*
X1439049Y87432D03*
X1454797D03*
X1446923D03*
G54D27*
X57646Y12480D03*
X137272D03*
X186622D03*
X266858D03*
X315598D03*
X502528Y33267D03*
X582154D03*
X631504D03*
X711740D03*
X760480D03*
X1183858Y207205D03*
Y217205D03*
X1173858D03*
X1193858Y207205D03*
Y217205D03*
X1351260Y164213D03*
Y174213D03*
X1361260Y164213D03*
Y174213D03*
X1371260Y164213D03*
X1381260D03*
X1371260Y174213D03*
X1381260D03*
X1391260Y164213D03*
X1532055Y12480D03*
X1611681D03*
X1661031D03*
X1741267D03*
X1790007D03*
G54D81*
X922441Y154311D03*
Y243799D03*
G54D19*
X38812Y547005D03*
X46292D03*
X272844Y1514077D03*
X280324D03*
X400906D03*
X408386D03*
X537571Y170765D03*
X545051D03*
X537017Y1514077D03*
X544497D03*
X553480Y131793D03*
X560960D03*
X1280717Y1547077D03*
X1288197D03*
X1408779D03*
X1416259D03*
X1544891D03*
X1552371D03*
G54D82*
X912209Y869555D03*
X903941D03*
X912209Y886681D03*
X903941D03*
X935789Y869792D03*
X944057D03*
X935789Y886918D03*
X944057D03*
X954866Y869937D03*
Y887063D03*
X963134Y869937D03*
Y887063D03*
G54D37*
X282204Y1548199D03*
X288004D03*
D03*
X293804D03*
X424115D03*
X418315D03*
X424115D03*
X429915D03*
X498356Y123068D03*
X504156D03*
X546377Y1548199D03*
X552177D03*
D03*
X557977D03*
X666870Y197272D03*
X672670D03*
X835765Y1276623D03*
X841565D03*
X955900Y1292000D03*
X950100D03*
X1290077Y1581199D03*
X1295877D03*
D03*
X1301677D03*
X1431989D03*
X1437789D03*
X1426189D03*
X1431989D03*
X1554251D03*
X1560051D03*
D03*
X1565851D03*
G54D55*
X535382Y772864D03*
X576559Y745141D03*
G54D64*
X660222Y1667233D03*
Y1672273D03*
X666128Y1667233D03*
Y1672273D03*
X942597Y936499D03*
X936691D03*
Y931459D03*
X942597D03*
G54D73*
X722569Y463948D03*
X719419D03*
X722568Y452844D03*
X725718D03*
X744536Y448279D03*
X741386D03*
X744536Y457649D03*
X741386D03*
X744536Y452844D03*
X741386D03*
G54D46*
X403163Y994332D03*
X494713Y1059772D03*
X1379479Y994292D03*
X1470919Y1059772D03*
G54D28*
X79729Y289822D03*
Y310256D03*
X89729Y289822D03*
Y310256D03*
X757184Y1702772D03*
Y1712772D03*
X1072863Y1409176D03*
Y1419176D03*
X1080970Y1640958D03*
Y1650958D03*
X1299439Y102812D03*
Y112812D03*
X1530377Y581353D03*
X1540377D03*
G54D91*
X1240449Y733779D03*
X1271146Y749877D03*
G54D47*
X401829Y1003273D03*
X445917Y971551D03*
X1378015Y1003283D03*
X1422059Y971550D03*
G54D83*
X906795Y869555D03*
X909355D03*
X906795Y886681D03*
X909355D03*
X941203Y869792D03*
X938643D03*
X941203Y886918D03*
X938643D03*
X960280Y869937D03*
X957720D03*
X960280Y887063D03*
X957720D03*
G54D65*
X662191Y1667233D03*
Y1672273D03*
X664159Y1667233D03*
Y1672273D03*
X938660Y936499D03*
X940628D03*
X938660Y931459D03*
X940628D03*
G54D74*
X735086Y448279D03*
Y445129D03*
X725718Y448279D03*
Y445129D03*
X730152Y448279D03*
Y445129D03*
X725718Y463948D03*
X735086Y463949D03*
Y460799D03*
X730152Y463948D03*
X725718Y467098D03*
X730152D03*
X738236Y463949D03*
Y460799D03*
G54D92*
X1249152Y60384D03*
X1431175Y87432D03*
G54D38*
X326731Y653394D03*
X363731D03*
X433624Y594259D03*
X754645Y1426892D03*
X1166535Y1412479D03*
X1291146Y1375715D03*
X1320516D03*
X1415690Y601230D03*
X1487677Y640145D03*
X1524437Y640365D03*
X1701285Y198612D03*
X1700840Y1424519D03*
X1731660Y198612D03*
X1770442Y284934D03*
X1800002D03*
G54D56*
X539016Y274272D03*
X549016D03*
X559016D03*
X569016D03*
X579016D03*
X589016D03*
X599016D03*
G54D29*
X80948Y525513D03*
Y521613D03*
X94474Y766871D03*
X108817Y1380530D03*
X124174Y766871D03*
X153875D03*
X183576D03*
X208818D03*
X262239Y649587D03*
X273208Y588237D03*
X430793Y686423D03*
X463193Y661823D03*
X474808Y291492D03*
X482893Y291293D03*
X495839Y635323D03*
X516020Y105370D03*
Y109270D03*
X535170Y111230D03*
Y115130D03*
X547821Y79372D03*
X551721D03*
X561808Y300492D03*
X569893Y300293D03*
X571063Y314669D03*
X634794Y590504D03*
X648314Y571169D03*
X644414D03*
X638694Y590504D03*
X650258Y590316D03*
X646358D03*
X642804Y766871D03*
X638053Y1384491D03*
X653101Y1369862D03*
X652651Y1375308D03*
X672505Y766871D03*
X690105Y401775D03*
X690452Y486984D03*
X704500Y529862D03*
X702206Y766871D03*
X716373Y1398539D03*
X739553Y388270D03*
X727448Y766871D03*
X745201Y1400702D03*
X770530Y423460D03*
X768301Y438223D03*
X770918Y442510D03*
X770042Y446829D03*
X761608Y766871D03*
X757826Y1514412D03*
X772610Y434690D03*
X772677Y451374D03*
X772427Y487344D03*
X786877Y427344D03*
X786999Y435476D03*
X791308Y766871D03*
X816550D03*
X833800Y444700D03*
X869275Y750472D03*
X873175D03*
X1025493Y761819D03*
Y765719D03*
X1040915Y766870D03*
X1070616D03*
X1080555Y1380511D03*
X1100316Y766870D03*
X1109201Y1382574D03*
X1112529Y1547661D03*
X1130017Y766870D03*
X1155282Y766806D03*
X1159718Y766870D03*
X1184960D03*
X1206580Y94846D03*
X1309870Y552788D03*
X1309776Y559831D03*
X1473408Y547948D03*
X1570021Y682038D03*
X1616084Y549105D03*
X1617200Y766870D03*
X1644188D03*
X1664106Y1397828D03*
X1673889Y766870D03*
X1692934Y1399991D03*
X1701661Y644554D03*
X1705561D03*
X1708049Y766870D03*
X1737850Y766794D03*
X1767450Y766870D03*
X1792692D03*
G54D57*
X591132Y1244425D03*
X582786Y1250725D03*
Y1244425D03*
X591132Y1250725D03*
X1560130Y1249812D03*
Y1243512D03*
X1568476D03*
Y1249812D03*
G54D48*
X415174Y105712D03*
Y113192D03*
X455534Y138539D03*
Y146019D03*
G54D93*
X1447227Y554649D03*
X1443487Y545987D03*
X1450967D03*
G54D75*
X736260Y1653665D03*
X740000Y1644335D03*
X743740Y1653665D03*
G54D84*
X909010Y924013D03*
X912947D03*
X907041D03*
X910978D03*
X907041Y934839D03*
X912947D03*
X909010D03*
X910978D03*
G54D66*
X695796Y430957D03*
Y437256D03*
Y468672D03*
X708395Y427807D03*
X705245Y437256D03*
X698946Y449854D03*
X708395Y456074D03*
Y478121D03*
Y471822D03*
Y484420D03*
X717843Y434106D03*
X720993Y427807D03*
Y468672D03*
X724143Y471822D03*
X714694Y468672D03*
X711544Y474971D03*
X724143Y481271D03*
X720993Y484420D03*
X727292Y424657D03*
X739811Y430957D03*
X733512Y471822D03*
X727292Y487570D03*
X755559Y421508D03*
X749260Y427807D03*
X752409Y440405D03*
Y462373D03*
X746110Y474971D03*
X752409Y478121D03*
X758709Y427807D03*
Y434106D03*
Y465523D03*
Y459223D03*
X765008Y474971D03*
X758709Y478121D03*
G54D39*
X326731Y663237D03*
X363731D03*
X443467Y594259D03*
X754645Y1436735D03*
X1077638Y133866D03*
X1166535Y1422322D03*
X1291146Y1385558D03*
X1320516D03*
X1425533Y601230D03*
X1487677Y649988D03*
X1524437Y650208D03*
X1701285Y208455D03*
X1700840Y1434362D03*
X1731660Y208455D03*
X1770442Y294777D03*
X1800002D03*
G54D58*
X599238Y1254075D03*
X609080D03*
X1586224Y1247707D03*
X1576382D03*
G54D76*
X733760Y1672685D03*
X737500D03*
X733760Y1683315D03*
X741240Y1672685D03*
Y1683315D03*
G54D94*
X1474107Y563127D03*
G54D49*
X417441Y1639260D03*
X420000D03*
X422559D03*
Y1646740D03*
X420000D03*
X417441D03*
X427441Y1637740D03*
X430000D03*
X427441Y1630260D03*
X432559D03*
X430000D03*
X432559Y1637740D03*
X657392Y1625582D03*
X654833D03*
X652274D03*
X657392Y1633062D03*
X652274D03*
X654833D03*
G54D67*
X690878Y1631636D03*
Y1634195D03*
Y1629077D03*
X698358Y1631636D03*
Y1634195D03*
Y1629077D03*
X731240Y565941D03*
Y568500D03*
X723760D03*
Y565941D03*
X731240Y571059D03*
X723760D03*
G54D85*
X909994Y929426D03*
G54D77*
X769895Y284264D03*
Y281705D03*
Y279146D03*
Y276587D03*
Y274028D03*
Y271469D03*
X764977Y298790D03*
Y296231D03*
X769895Y286823D03*
X764977Y311585D03*
Y309026D03*
Y306467D03*
Y303908D03*
Y301349D03*
X792895Y271469D03*
Y274028D03*
Y276587D03*
Y279146D03*
Y281705D03*
Y284264D03*
X787977Y296231D03*
Y298790D03*
X792895Y286823D03*
X787977Y301349D03*
Y303908D03*
Y306467D03*
Y309026D03*
Y311585D03*
X812499Y299070D03*
Y296511D03*
Y311865D03*
Y309306D03*
Y306747D03*
Y304188D03*
Y301629D03*
X818575Y268624D03*
Y266065D03*
Y281419D03*
Y278860D03*
Y276301D03*
Y273742D03*
Y271183D03*
X841575Y266065D03*
Y268624D03*
Y271183D03*
Y273742D03*
Y276301D03*
Y278860D03*
Y281419D03*
X835499Y296511D03*
Y299070D03*
Y301629D03*
Y304188D03*
Y306747D03*
Y309306D03*
Y311865D03*
G54D68*
X693193Y1651089D03*
Y1648530D03*
Y1645970D03*
Y1643411D03*
X710771Y1648530D03*
Y1645970D03*
Y1643411D03*
Y1651089D03*
G54D95*
X1462113Y1668854D03*
Y1663854D03*
Y1678854D03*
Y1673854D03*
X1482585Y1663854D03*
Y1668854D03*
Y1673854D03*
Y1678854D03*
G54D86*
X914623Y1266833D03*
X911473D03*
X908323D03*
X911473D03*
X914737Y1271025D03*
X911587D03*
X908437D03*
X911587D03*
X908159Y1283775D03*
X911309D03*
X914459D03*
X911309D03*
X908199Y1279451D03*
X911349D03*
X914499D03*
X911349D03*
X908168Y1275251D03*
X911318D03*
X914468D03*
X911318D03*
X907988Y1296713D03*
X911138D03*
X914288D03*
X911138D03*
X908008Y1292330D03*
X911158D03*
X914308D03*
X911158D03*
X908075Y1288235D03*
X911225D03*
X914375D03*
X911225D03*
X923962Y839601D03*
X920812D03*
X924075Y847191D03*
X920925D03*
X923962Y839601D03*
X927112D03*
X924075Y847191D03*
X927225D03*
X918425Y893000D03*
X921575D03*
X924725D03*
X921575D03*
X918425Y898000D03*
X921575D03*
X924725D03*
X921575D03*
X930775Y982500D03*
Y977500D03*
X933925Y982500D03*
Y977500D03*
Y982500D03*
X937075D03*
X933925Y977500D03*
X937075D03*
X1571182Y1278788D03*
X1568032D03*
X1564882D03*
X1568032D03*
X1586282Y1275168D03*
X1592582D03*
X1589432D03*
D03*
G54D59*
X609016Y274272D03*
G54D69*
X690500Y1671063D03*
X694240Y1678937D03*
X686760D03*
X1443487Y568881D03*
X1450967D03*
X1447227Y576755D03*
G54D78*
X788941Y549260D03*
X791500D03*
X794059D03*
Y556740D03*
X791500D03*
X788941D03*
G54D87*
X973423Y1283193D03*
Y1280693D03*
Y1278193D03*
Y1275693D03*
Y1273193D03*
Y1290693D03*
Y1288193D03*
Y1285693D03*
X994329Y1273193D03*
Y1275693D03*
Y1278193D03*
Y1280693D03*
Y1283193D03*
Y1285693D03*
Y1288193D03*
Y1290693D03*
G54D96*
X1504000Y812640D03*
G54D97*
X1551887Y610299D03*
Y602819D03*
X1559761Y606559D03*
G54D79*
X864599Y1281729D03*
Y1279170D03*
Y1276611D03*
Y1294525D03*
Y1291966D03*
Y1289407D03*
Y1286848D03*
Y1284288D03*
X886647Y1276611D03*
Y1279170D03*
Y1281729D03*
Y1284288D03*
Y1286848D03*
Y1289407D03*
Y1291966D03*
Y1294525D03*
G54D88*
X1156378Y133866D03*
X1173858Y207205D03*
X1391260Y174213D03*
G54D98*
X1567913Y593271D03*
Y605869D03*
X1576213Y593271D03*
X1584513D03*
X1576213Y605869D03*
X1584513D03*
X1592813Y593271D03*
Y605869D03*
G54D89*
X1207600Y1394000D03*
X1665904Y1949823D03*
G54D99*
X1579532Y793506D03*
Y800986D03*
X1589178D03*
Y793506D03*
Y797246D03*
X1587601Y1337293D03*
Y1344773D03*
Y1351773D03*
Y1359253D03*
X1597247Y1337293D03*
Y1341033D03*
Y1344773D03*
Y1351773D03*
Y1355513D03*
Y1359253D03*
M02*
